%FSTAX23Y23*%
%MOIN*%
%SFA1B1*%

%IPPOS*%
%ADD13C,0.010000*%
%ADD19C,0.008000*%
%ADD21C,0.005000*%
%ADD50R,0.028000X0.165000*%
%ADD51R,0.028000X0.126000*%
%ADD62R,0.057090X0.045280*%
%ADD64R,0.025200X0.026770*%
%ADD71R,0.045280X0.057090*%
%ADD72R,0.026770X0.025200*%
%ADD77R,0.082870X0.044090*%
%ADD143C,0.120000*%
%ADD153C,0.020000*%
%ADD156C,0.031500*%
%ADD157C,0.065980*%
%ADD158C,0.061020*%
%ADD159R,0.061020X0.061020*%
%ADD160C,0.075000*%
%ADD161C,0.098430*%
%ADD162O,0.088580X0.177170*%
%ADD163O,0.177170X0.088580*%
%ADD164O,0.196850X0.098430*%
%ADD165C,0.112000*%
%ADD166C,0.021660*%
%ADD167C,0.055000*%
%ADD168R,0.055000X0.055000*%
%ADD169C,0.050000*%
%ADD170C,0.250000*%
%ADD171C,0.016000*%
%ADD172C,0.200000*%
%ADD173R,0.073820X0.067910*%
%LNgrandmaster-1*%
%LPD*%
G36*
X04349Y04334D02*
X02014D01*
X02011Y04333*
X02009Y04331*
X02007Y04329*
X02006Y04326*
Y04293*
X02007Y0429*
X02007Y04289*
Y04226*
X02007Y04225*
X02006Y04222*
Y04186*
X02006Y04185*
X02007Y04184*
X02007Y04184*
X02007Y04183*
X02008Y04182*
X02008Y04181*
X02008Y04181*
X02009Y04181*
X02009Y0418*
X0201Y04179*
X02012Y04175*
X02008Y04167*
X02007Y04157*
X02008Y04148*
X02012Y04139*
X0201Y04135*
X02009Y04135*
X02009Y04134*
X02008Y04134*
X02008Y04134*
X02008Y04133*
X02007Y04131*
X02007Y04131*
X02007Y04131*
X02006Y0413*
X02006Y04128*
Y04086*
X02006Y04085*
X02007Y04084*
X02007Y04084*
X02007Y04083*
X02008Y04082*
X02008Y04081*
X02008Y04081*
X02009Y04081*
X02009Y0408*
X0201Y04079*
X02012Y04075*
X02008Y04067*
X02007Y04057*
X02008Y04048*
X02012Y04039*
X0201Y04035*
X02009Y04035*
X02009Y04034*
X02008Y04034*
X02008Y04034*
X02008Y04033*
X02007Y04031*
X02007Y04031*
X02007Y04031*
X02006Y0403*
X02006Y04028*
Y0385*
X02006Y03849*
X02007Y03847*
X02007Y03847*
X02007Y03847*
X02008Y03846*
X02009Y03844*
X02009Y03844*
X02009Y03844*
X0201Y03844*
X02011Y03843*
X02014Y03841*
X02013Y03836*
X02013Y03835*
X02013Y03834*
X02009Y03831*
X02004Y03832*
X01998Y03831*
X01993Y03827*
X01989Y03822*
X01988Y03816*
X01989Y03809*
X01993Y03804*
X01998Y038*
X02004Y03799*
X02006Y03798*
Y02718*
X02007Y02714*
X02009Y02712*
X02011Y0271*
X02014Y02709*
X02349*
X02352Y0271*
X02355Y02712*
X02357Y02714*
X02358Y02718*
Y02833*
X02387*
X02402Y02818*
Y02792*
X02403Y02789*
X02402Y02788*
X02404Y02782*
X02407Y02777*
X02413Y02773*
X02419Y02772*
X02425Y02773*
X0243Y02777*
X02431Y02777*
X02437Y02777*
X02443Y02766*
X02454Y02753*
X02467Y02742*
X02482Y02733*
X02497Y02727*
X02514Y02723*
X02531Y02721*
X02548Y02723*
X02564Y02727*
X0258Y02733*
X02595Y02742*
X02608Y02753*
X02619Y02766*
X02627Y0278*
X02634Y02796*
X02638Y02813*
X02639Y0283*
X02638Y02846*
X02635Y02857*
X02638Y0286*
X02643Y02864*
X02646Y02869*
X02648Y02876*
X02646Y02882*
X02646Y02883*
Y0294*
X02669*
Y02959*
X02681*
X02685Y0296*
X02689Y02962*
X02708Y02981*
X02732*
Y03024*
X02691*
Y02999*
X02676Y02983*
X02669*
Y03002*
X02596*
Y0294*
X02619*
Y029*
X02614Y02898*
X02608Y02906*
X02595Y02917*
X0258Y02926*
X02564Y02933*
X02548Y02937*
X02531Y02938*
X02514Y02937*
X02497Y02933*
X02482Y02926*
X02467Y02917*
X02454Y02906*
X02443Y02893*
X02434Y02879*
X02428Y02863*
X02424Y02846*
X02423Y02841*
X02419Y02839*
X02407Y02851*
Y02874*
X02358*
Y02907*
X02358*
Y0298*
X02358*
Y03012*
X02384*
Y03072*
X02358*
Y03091*
X02384*
Y03109*
X02405*
X02407Y03106*
X02408Y03106*
Y031*
X02405Y03098*
X024Y03091*
X02398Y03082*
X024Y03073*
X02405Y03065*
X02413Y0306*
X02422Y03058*
X02431Y0306*
X02438Y03065*
X02443Y03073*
X02445Y03082*
X02443Y03091*
X02438Y03098*
X02432Y03102*
X02431Y03105*
X02431Y03108*
X02433Y03112*
X02435Y03118*
X02433Y03124*
X0243Y0313*
X02424Y03133*
X02418Y03134*
X02413Y03133*
X02384*
Y03151*
X02358*
Y0317*
X02384*
Y03187*
X02403*
X02407Y03184*
X02414Y03183*
X0242Y03184*
X02425Y03188*
X02429Y03193*
X0243Y03199*
X02429Y03206*
X02425Y03211*
X02425Y03211*
X02426Y03217*
X02431Y03218*
X02438Y03223*
X02443Y0323*
X02445Y03239*
X02443Y03248*
X02438Y03256*
X02431Y03261*
X02422Y03263*
X02413Y03261*
X02405Y03256*
X024Y03248*
X02398Y03239*
X024Y0323*
X02405Y03223*
X02409Y0322*
X02408Y03215*
X02407Y03214*
X02403Y03212*
X02384*
Y0323*
X02358*
Y03249*
X02384*
Y03265*
X02397*
X02402Y03266*
X02407Y03269*
X02416Y03279*
X0242Y03279*
X02425Y03283*
X02428Y03288*
X0243Y03295*
X02428Y03301*
X02425Y03306*
X0242Y0331*
X02413Y03311*
X02407Y0331*
X02402Y03306*
X02398Y03301*
X02398Y03298*
X02392Y03292*
X02384*
Y03309*
X02358*
Y03322*
X02674Y03639*
X02674Y03639*
X02675Y03639*
X02675Y0364*
X02676Y03641*
X02676Y03642*
X02676Y03642*
X02679Y03644*
X02686Y03645*
X02691Y03649*
X02694Y03654*
X02695Y03659*
X02696Y03661*
X02698Y03664*
X02698Y03664*
X02699Y03664*
X027Y03665*
X02701Y03665*
X02701Y03666*
X02701Y03666*
X02713Y03677*
X0352*
X03522Y03672*
X0352Y03671*
X03516Y03666*
X03515Y0366*
X03516Y03653*
X0352Y03648*
X03525Y03644*
X03531Y03643*
X03538Y03644*
X03543Y03648*
X03546Y03653*
X03548Y0366*
X03546Y03666*
X03543Y03671*
X03541Y03672*
X03542Y03677*
X03804*
X03807Y03678*
X0381Y0368*
Y0368*
X03913Y03783*
X03915Y03786*
X03916Y03789*
X0392Y03793*
X03939*
X04037Y03696*
Y03675*
X04034Y03671*
X04033Y03665*
X04034Y03658*
X04038Y03653*
X04043Y03649*
X04049Y03648*
X04056Y03649*
X04061Y03653*
X04064Y03658*
X04066Y03665*
X04064Y03671*
X04062Y03675*
Y03701*
X04061Y03705*
X04058Y03709*
X03953Y03814*
X03952Y03815*
X03951Y03821*
X04068Y03937*
X04181*
X04341Y03777*
Y03662*
X0385Y03171*
X03845Y03174*
X03846Y03176*
X03844Y03182*
X03841Y03187*
X03836Y03191*
X03829Y03192*
X03823Y03191*
X03818Y03187*
X03814Y03182*
X03813Y03176*
X03814Y03169*
X03818Y03164*
X03823Y0316*
X03829Y03159*
X03831Y0316*
X03834Y03155*
X03824Y03146*
Y02201*
X04154Y01871*
X06687*
X06688Y01869*
X06693Y01865*
X06699Y01864*
X06706Y01865*
X06711Y01869*
X06712Y01871*
X06901*
Y01649*
X06637Y01385*
X06635Y01387*
X06628Y01388*
X06622Y01387*
X06617Y01383*
X06613Y01378*
X06612Y01372*
X06613Y01365*
X06615Y01363*
X06584Y01331*
X06582Y01329*
X06581Y01326*
Y01241*
X06582Y01237*
X06584Y01235*
X06644Y01175*
X06646Y01173*
X06649Y01172*
X06779*
X06782Y01173*
X06785Y01175*
X0693Y01319*
X06934Y01317*
Y01216*
X06329Y00611*
X03784*
X02638Y01757*
X02638Y01758*
X02641Y01763*
X02643Y0177*
X02641Y01776*
X02638Y01781*
X02633Y01785*
X02626Y01786*
X0262Y01785*
X02615Y01781*
X02614Y01781*
X02425Y0197*
X02424Y01973*
X02421Y01978*
X02416Y01982*
X02413Y01982*
X01355Y0304*
Y04162*
X01357Y04163*
X0136Y04168*
X01361Y04175*
X0136Y04181*
X01357Y04186*
X01355Y04187*
Y04341*
X01709*
X01712Y04336*
X01711Y04335*
X0171Y04329*
X01711Y04323*
X01715Y04317*
X0172Y04314*
X01726Y04313*
X01733Y04314*
X01738Y04317*
X01741Y04323*
X01743Y04329*
X01741Y04335*
X01741Y04336*
X01744Y04341*
X01771*
X01774Y04336*
X01773Y04335*
X01772Y04329*
X01773Y04323*
X01777Y04317*
X01782Y04314*
X01788Y04313*
X01795Y04314*
X018Y04317*
X01803Y04323*
X01805Y04329*
X01803Y04335*
X01803Y04336*
X01806Y04341*
X04349*
Y04334*
G37*
G36*
X06504Y04151D02*
Y04111D01*
X06503Y04106*
X06502Y04093*
X06503Y0408*
X06504Y04075*
Y0372*
X06501Y03716*
X06314Y03717*
X06313Y03717*
X06312Y03717*
X06311Y03717*
X0631Y03717*
X0631Y03716*
X06309Y03716*
X06309Y03715*
X06308Y03715*
X06307Y03714*
X06307Y03714*
X06306Y03712*
X06301Y03716*
X06294Y03717*
X06288Y03716*
X06286Y03714*
X06281Y03715*
X0628Y03715*
X0628Y03716*
X06279Y03716*
X06278Y03717*
X06278Y03717*
X06277Y03717*
X06276Y03717*
X06275Y03717*
X05989Y03719*
X05989*
X05989*
X05988Y03718*
X05986Y03718*
X05986Y03718*
X05986*
X05985Y03717*
X05984Y03716*
X05984Y03716*
X05984Y03716*
X05874Y03606*
X05872Y03604*
X05871Y03601*
Y03451*
X05872Y03447*
X05874Y03445*
X06326Y02992*
Y02397*
X06304Y02376*
X06289*
X06287Y02381*
X06289Y02384*
X06291Y02391*
X06289Y02397*
X06286Y02402*
X06281Y02406*
X06274Y02407*
X06268Y02406*
X06263Y02402*
X06259Y02397*
X06258Y02391*
X06259Y02384*
X06262Y02381*
X0626Y02376*
X04639*
X04349Y02666*
Y02712*
X04351Y02713*
X04354Y02718*
X04356Y02725*
X04354Y02731*
X04351Y02736*
X04349Y02737*
Y03133*
X0435Y03135*
X04349Y03136*
Y03781*
X04184Y03946*
X04064*
X03937Y03818*
X0384*
X03836Y03821*
X03829Y03822*
X03823Y03821*
X03818Y03817*
X03814Y03812*
X03813Y03806*
X03814Y03799*
X03818Y03794*
X03823Y0379*
X03829Y03789*
X03836Y0379*
X0384Y03793*
X03906*
X03907Y03789*
X03804Y03686*
X02709*
X02695Y03672*
X02691Y03672*
X02686Y03676*
X02679Y03677*
X02673Y03676*
X02668Y03672*
X02664Y03667*
X02663Y03661*
X02664Y03654*
X02668Y03649*
X02668Y03644*
X02349Y03326*
Y03309*
X02285*
Y03249*
X02349*
Y0323*
X02285*
Y0317*
X02349*
Y03151*
X02285*
Y03091*
X02349*
Y02718*
X02014*
Y03803*
X02016Y03804*
X02019Y03809*
X02021Y03816*
X02021Y03816*
X02021Y03817*
X02025Y0382*
X02029Y03819*
X02036Y0382*
X02041Y03824*
X02044Y03829*
X02046Y03836*
X02044Y03842*
X02041Y03847*
X02036Y03851*
X02029Y03852*
X02023Y03851*
X02019Y03848*
X02014Y0385*
Y04028*
X02019Y04031*
X02025Y04026*
X02034Y04023*
X02043Y04022*
X02052Y04023*
X02061Y04026*
X02068Y04032*
X02074Y04039*
X02077Y04048*
X02079Y04057*
X02077Y04067*
X02074Y04075*
X02068Y04083*
X02061Y04088*
X02052Y04092*
X02043Y04093*
X02034Y04092*
X02025Y04088*
X02019Y04084*
X02014Y04086*
Y04128*
X02019Y04131*
X02025Y04126*
X02034Y04123*
X02043Y04122*
X02052Y04123*
X02061Y04126*
X02068Y04132*
X02074Y04139*
X02077Y04148*
X02079Y04157*
X02077Y04167*
X02074Y04175*
X02068Y04183*
X02061Y04188*
X02052Y04192*
X02043Y04193*
X02034Y04192*
X02025Y04188*
X02019Y04184*
X02014Y04186*
Y04222*
X02078*
Y04293*
X02014*
Y04326*
X06329*
X06504Y04151*
G37*
G36*
X06275Y03709D02*
X06279Y03704D01*
X06278Y03701*
X06279Y03694*
X06283Y03689*
X06288Y03685*
X06294Y03684*
X06301Y03685*
X06306Y03689*
X06309Y03694*
X06311Y03701*
X0631Y03704*
X06314Y03709*
X07024Y03706*
X07087Y03643*
Y01488*
X06779Y01181*
X06649*
X06589Y01241*
Y01326*
X06621Y01357*
X06622Y01356*
X06628Y01355*
X06635Y01356*
X0664Y0136*
X06643Y01365*
X06645Y01372*
X06643Y01378*
X06643Y01379*
X06909Y01646*
Y01991*
X06819Y02081*
X06409*
X06399Y02091*
X06401Y02095*
X06402Y02095*
X06407Y02099*
X0641Y02104*
X06412Y02111*
X0641Y02117*
X06407Y02122*
X06402Y02126*
X06395Y02127*
X06389Y02126*
X06384Y02122*
X0638Y02117*
X0638Y02116*
X06375Y02115*
X06334Y02156*
Y02996*
X05879Y03451*
Y03601*
X05989Y03711*
X06275Y03709*
G37*
%LNgrandmaster-2*%
%LPC*%
G36*
X01493Y04289D02*
X01422D01*
Y04218*
X01493*
Y04289*
G37*
G36*
X01569Y04187D02*
X01563Y04186D01*
X01558Y04182*
X01554Y04177*
X01553Y04171*
X01554Y04165*
X01558Y04159*
X01563Y04156*
X01569Y04154*
X01576Y04156*
X01581Y04159*
X01584Y04165*
X01586Y04171*
X01584Y04177*
X01581Y04182*
X01576Y04186*
X01569Y04187*
G37*
G36*
X01779Y04172D02*
X01773Y04171D01*
X01768Y04167*
X01764Y04162*
X01763Y04156*
X01764Y04149*
X01768Y04144*
X01773Y0414*
X01779Y04139*
X01786Y0414*
X01791Y04144*
X01794Y04149*
X01796Y04156*
X01794Y04162*
X01791Y04167*
X01786Y04171*
X01779Y04172*
G37*
G36*
X01457Y04189D02*
X01448Y04188D01*
X01439Y04184*
X01432Y04179*
X01426Y04171*
X01423Y04163*
X01421Y04153*
X01423Y04144*
X01426Y04136*
X01432Y04128*
X01439Y04122*
X01448Y04119*
X01457Y04118*
X01466Y04119*
X01475Y04122*
X01483Y04128*
X01488Y04136*
X01492Y04144*
X01493Y04153*
X01492Y04163*
X01488Y04171*
X01483Y04179*
X01475Y04184*
X01466Y04188*
X01457Y04189*
G37*
G36*
X01749Y04126D02*
X01743Y04125D01*
X01738Y04121*
X01734Y04116*
X01733Y0411*
X01734Y04103*
X01738Y04098*
X01743Y04094*
X01749Y04093*
X01756Y04094*
X01761Y04098*
X01764Y04103*
X01766Y0411*
X01764Y04116*
X01761Y04121*
X01756Y04125*
X01749Y04126*
G37*
G36*
X01691Y04095D02*
X01685Y04094D01*
X0168Y0409*
X01676Y04085*
X01675Y04079*
X01676Y04072*
X0168Y04067*
X01685Y04063*
X01691Y04062*
X01698Y04063*
X01703Y04067*
X01706Y04072*
X01708Y04079*
X01706Y04085*
X01703Y0409*
X01698Y04094*
X01691Y04095*
G37*
G36*
X01457Y04089D02*
X01448Y04088D01*
X01439Y04084*
X01432Y04079*
X01426Y04071*
X01423Y04063*
X01421Y04053*
X01423Y04044*
X01426Y04036*
X01432Y04028*
X01439Y04022*
X01448Y04019*
X01457Y04018*
X01466Y04019*
X01475Y04022*
X01483Y04028*
X01488Y04036*
X01492Y04044*
X01493Y04053*
X01492Y04063*
X01488Y04071*
X01483Y04079*
X01475Y04084*
X01466Y04088*
X01457Y04089*
G37*
G36*
X01903Y04034D02*
X01897Y04033D01*
X01892Y04029*
X01888Y04024*
X01887Y04018*
X01888Y04011*
X01892Y04006*
X01897Y04002*
X01903Y04001*
X0191Y04002*
X01915Y04006*
X01918Y04011*
X0192Y04018*
X01918Y04024*
X01915Y04029*
X0191Y04033*
X01903Y04034*
G37*
G36*
X01408Y03996D02*
X01402Y03995D01*
X01396Y03991*
X01393Y03986*
X01392Y0398*
X01393Y03974*
X01396Y03968*
X01402Y03965*
X01408Y03964*
X01414Y03965*
X0142Y03968*
X01423Y03974*
X01424Y0398*
X01423Y03986*
X0142Y03991*
X01414Y03995*
X01408Y03996*
G37*
G36*
X04085Y03908D02*
X04079Y03907D01*
X04074Y03903*
X0407Y03898*
X04069Y03892*
X0407Y03885*
X04074Y0388*
X04079Y03876*
X04085Y03875*
X04092Y03876*
X04097Y0388*
X041Y03885*
X04102Y03892*
X041Y03898*
X04097Y03903*
X04092Y03907*
X04085Y03908*
G37*
G36*
X04194Y039D02*
X04188Y03899D01*
X04183Y03895*
X04179Y0389*
X04178Y03884*
X04179Y03877*
X04183Y03872*
X04188Y03868*
X04194Y03867*
X04201Y03868*
X04206Y03872*
X04209Y03877*
X04211Y03884*
X04209Y0389*
X04206Y03895*
X04201Y03899*
X04194Y039*
G37*
G36*
X04039Y038D02*
X04033Y03799D01*
X04028Y03795*
X04024Y0379*
X04023Y03784*
X04024Y03777*
X04028Y03772*
X04033Y03768*
X04039Y03767*
X04046Y03768*
X04051Y03772*
X04054Y03777*
X04056Y03784*
X04054Y0379*
X04051Y03795*
X04046Y03799*
X04039Y038*
G37*
G36*
X01849Y03717D02*
X01843Y03716D01*
X01838Y03712*
X01834Y03707*
X01833Y03701*
X01834Y03694*
X01838Y03689*
X01843Y03685*
X01849Y03684*
X01856Y03685*
X01861Y03689*
X01864Y03694*
X01866Y03701*
X01864Y03707*
X01861Y03712*
X01856Y03716*
X01849Y03717*
G37*
G36*
X01754Y03677D02*
X01748Y03676D01*
X01743Y03672*
X01739Y03667*
X01738Y03661*
X01739Y03654*
X01743Y03649*
X01748Y03645*
X01754Y03644*
X01761Y03645*
X01766Y03649*
X01769Y03654*
X01771Y03661*
X01769Y03667*
X01766Y03672*
X01761Y03676*
X01754Y03677*
G37*
G36*
X03424Y03652D02*
X03418Y03651D01*
X03413Y03647*
X03409Y03642*
X03408Y03636*
X03409Y03629*
X03413Y03624*
X03418Y0362*
X03424Y03619*
X03431Y0362*
X03436Y03624*
X03439Y03629*
X03441Y03636*
X03439Y03642*
X03436Y03647*
X03431Y03651*
X03424Y03652*
G37*
G36*
X02799Y03632D02*
X02793Y03631D01*
X02788Y03627*
X02784Y03622*
X02783Y03616*
X02784Y03609*
X02788Y03604*
X02793Y036*
X02799Y03599*
X02806Y036*
X02811Y03604*
X02814Y03609*
X02816Y03616*
X02814Y03622*
X02811Y03627*
X02806Y03631*
X02799Y03632*
G37*
G36*
X01884Y03617D02*
X01878Y03616D01*
X01873Y03612*
X01869Y03607*
X01868Y03601*
X01869Y03594*
X01873Y03589*
X01878Y03585*
X01884Y03584*
X01891Y03585*
X01896Y03589*
X01899Y03594*
X01901Y03601*
X01899Y03607*
X01896Y03612*
X01891Y03616*
X01884Y03617*
G37*
G36*
X03239Y03612D02*
X03233Y03611D01*
X03228Y03607*
X03224Y03602*
X03223Y03596*
X03224Y03589*
X03228Y03584*
X03233Y0358*
X03239Y03579*
X03246Y0358*
X03251Y03584*
X03254Y03589*
X03256Y03596*
X03254Y03602*
X03251Y03607*
X03246Y03611*
X03239Y03612*
G37*
G36*
X01549Y03637D02*
X01543Y03636D01*
X01538Y03632*
X01534Y03627*
X01533Y03621*
X01534Y03614*
X01538Y03609*
X01543Y03605*
X01549Y03604*
X01556Y03605*
X01556Y03606*
X01559Y03602*
X01559Y03602*
X01558Y03596*
X01559Y03589*
X01563Y03584*
X01568Y0358*
X01574Y03579*
X01581Y0358*
X01586Y03584*
X01589Y03589*
X01591Y03596*
X01589Y03602*
X01586Y03607*
X01581Y03611*
X01574Y03612*
X01568Y03611*
X01568Y0361*
X01564Y03614*
X01564Y03614*
X01566Y03621*
X01564Y03627*
X01561Y03632*
X01556Y03636*
X01549Y03637*
G37*
G36*
X0412Y0361D02*
X04114Y03609D01*
X04108Y03605*
X04105Y036*
X04104Y03594*
X04105Y03587*
X04108Y03582*
X04114Y03579*
X0412Y03577*
X04126Y03579*
X04131Y03582*
X04135Y03587*
X04136Y03594*
X04135Y036*
X04131Y03605*
X04126Y03609*
X0412Y0361*
G37*
G36*
X0144Y03573D02*
X01434Y03572D01*
X01429Y03568*
X01425Y03563*
X01424Y03557*
X01425Y0355*
X01429Y03545*
X01434Y03541*
X0144Y0354*
X01447Y03541*
X01452Y03545*
X01455Y0355*
X01457Y03557*
X01455Y03563*
X01452Y03568*
X01447Y03572*
X0144Y03573*
G37*
G36*
X02724Y03537D02*
X02718Y03536D01*
X02713Y03532*
X02709Y03527*
X02708Y03521*
X02709Y03514*
X02713Y03509*
X02718Y03505*
X02724Y03504*
X02731Y03505*
X02736Y03509*
X02739Y03514*
X02741Y03521*
X02739Y03527*
X02736Y03532*
X02731Y03536*
X02724Y03537*
G37*
G36*
X02674Y03517D02*
X02668Y03516D01*
X02663Y03512*
X02659Y03507*
X02658Y03501*
X02659Y03494*
X02663Y03489*
X02668Y03485*
X02674Y03484*
X02681Y03485*
X02686Y03489*
X02689Y03494*
X02691Y03501*
X02689Y03507*
X02686Y03512*
X02681Y03516*
X02674Y03517*
G37*
G36*
X03622Y03502D02*
X03616Y03501D01*
X03611Y03497*
X03607Y03492*
X03606Y03486*
X03607Y03479*
X03611Y03474*
X03616Y0347*
X03622Y03469*
X03629Y0347*
X03634Y03474*
X03637Y03479*
X03639Y03486*
X03637Y03492*
X03634Y03497*
X03629Y03501*
X03622Y03502*
G37*
G36*
X02579D02*
X02573Y03501D01*
X02568Y03497*
X02564Y03492*
X02563Y03486*
X02564Y03479*
X02568Y03474*
X02573Y0347*
X02579Y03469*
X02586Y0347*
X02591Y03474*
X02594Y03479*
X02596Y03486*
X02594Y03492*
X02591Y03497*
X02586Y03501*
X02579Y03502*
G37*
G36*
X03529Y03497D02*
X03523Y03496D01*
X03518Y03492*
X03514Y03487*
X03513Y03481*
X03514Y03474*
X03518Y03469*
X03523Y03465*
X03529Y03464*
X03536Y03465*
X03541Y03469*
X03544Y03474*
X03546Y03481*
X03544Y03487*
X03541Y03492*
X03536Y03496*
X03529Y03497*
G37*
G36*
X03436Y03473D02*
X0343Y03472D01*
X03425Y03468*
X03421Y03463*
X0342Y03457*
X03421Y0345*
X03425Y03445*
X0343Y03441*
X03436Y0344*
X03443Y03441*
X03448Y03445*
X0345Y03448*
X0345Y03448*
X03456Y03447*
X03458Y03444*
X03463Y0344*
X03469Y03439*
X03476Y0344*
X03481Y03444*
X03484Y03449*
X03486Y03456*
X03484Y03462*
X03481Y03467*
X03476Y03471*
X03469Y03472*
X03463Y03471*
X03458Y03467*
X03456Y03464*
X03456Y03464*
X0345Y03465*
X03448Y03468*
X03443Y03472*
X03436Y03473*
G37*
G36*
X03358Y03464D02*
X03352Y03463D01*
X03347Y03459*
X03343Y03454*
X03342Y03448*
X03343Y03441*
X03347Y03436*
X03352Y03432*
X03358Y03431*
X03365Y03432*
X0337Y03436*
X03373Y03441*
X03374Y03443*
X03379*
X03379Y0344*
X03383Y03435*
X03388Y03431*
X03394Y0343*
X03401Y03431*
X03406Y03435*
X03409Y0344*
X03411Y03447*
X03409Y03453*
X03406Y03458*
X03401Y03462*
X03394Y03463*
X03388Y03462*
X03383Y03458*
X03379Y03453*
X03379Y03451*
X03374*
X03373Y03454*
X0337Y03459*
X03365Y03463*
X03358Y03464*
G37*
G36*
X02634Y03422D02*
X02628Y03421D01*
X02623Y03417*
X02619Y03412*
X02618Y03406*
X02619Y03399*
X02623Y03394*
X02628Y0339*
X02634Y03389*
X02641Y0339*
X02646Y03394*
X02649Y03399*
X02651Y03406*
X02649Y03412*
X02646Y03417*
X02641Y03421*
X02634Y03422*
G37*
G36*
X03068Y03411D02*
X03062Y0341D01*
X03057Y03407*
X03053Y03401*
X03052Y03395*
X03053Y03389*
X03057Y03384*
X03062Y0338*
X03068Y03379*
X03075Y0338*
X0308Y03384*
X03083Y03389*
X03085Y03395*
X03083Y03401*
X0308Y03407*
X03075Y0341*
X03068Y03411*
G37*
G36*
X03302Y0336D02*
X03296Y03359D01*
X03291Y03355*
X03287Y0335*
X03286Y03344*
X03287Y03337*
X03291Y03332*
X03296Y03328*
X03302Y03327*
X03309Y03328*
X03314Y03332*
X03317Y03337*
X03319Y03344*
X03317Y0335*
X03314Y03355*
X03309Y03359*
X03302Y0336*
G37*
G36*
X03744Y03358D02*
X03738Y03357D01*
X03733Y03353*
X03729Y03348*
X03728Y03342*
X03729Y03335*
X03733Y0333*
X03738Y03326*
X03744Y03325*
X03751Y03326*
X03756Y0333*
X03759Y03335*
X03761Y03342*
X03759Y03348*
X03756Y03353*
X03751Y03357*
X03744Y03358*
G37*
G36*
X03542Y03335D02*
X03536Y03334D01*
X03531Y0333*
X03527Y03325*
X03526Y03319*
X03527Y03312*
X03531Y03307*
X03536Y03303*
X03542Y03302*
X03549Y03303*
X03554Y03307*
X03557Y03312*
X03559Y03319*
X03557Y03325*
X03554Y0333*
X03549Y03334*
X03542Y03335*
G37*
G36*
X03263Y0332D02*
X03257Y03318D01*
X03252Y03315*
X03248Y0331*
X03247Y03303*
X03248Y03297*
X03252Y03292*
X03257Y03288*
X03263Y03287*
X03269Y03288*
X03275Y03292*
X03278Y03297*
X0328Y03303*
X03278Y0331*
X03275Y03315*
X03269Y03318*
X03263Y0332*
G37*
G36*
X0333Y03317D02*
X03324Y03316D01*
X03319Y03312*
X03315Y03307*
X03314Y03301*
X03315Y03294*
X03319Y03289*
X03324Y03285*
X0333Y03284*
X03337Y03285*
X03342Y03289*
X03345Y03294*
X03347Y03301*
X03345Y03307*
X03342Y03312*
X03337Y03316*
X0333Y03317*
G37*
G36*
X03491Y03313D02*
X03485Y03312D01*
X0348Y03308*
X03476Y03303*
X03475Y03297*
X03476Y0329*
X0348Y03285*
X03485Y03281*
X03491Y0328*
X03498Y03281*
X03503Y03285*
X03506Y0329*
X03508Y03297*
X03506Y03303*
X03503Y03308*
X03498Y03312*
X03491Y03313*
G37*
G36*
X03653Y03309D02*
X03647Y03308D01*
X03642Y03304*
X03638Y03299*
X03637Y03293*
X03638Y03286*
X03642Y03281*
X03647Y03277*
X03653Y03276*
X0366Y03277*
X03665Y03281*
X03668Y03286*
X0367Y03293*
X03668Y03299*
X03665Y03304*
X0366Y03308*
X03653Y03309*
G37*
G36*
X03374Y03289D02*
X03368Y03288D01*
X03363Y03284*
X03359Y03279*
X03358Y03273*
X03359Y03266*
X03363Y03261*
X03368Y03257*
X03374Y03256*
X03381Y03257*
X03386Y03261*
X03389Y03266*
X03391Y03273*
X03389Y03279*
X03386Y03284*
X03381Y03288*
X03374Y03289*
G37*
G36*
X02559Y03309D02*
X0246D01*
Y03249*
X02559*
Y03266*
X02583*
X02588Y03267*
X02592Y0327*
X02594Y03272*
X02597Y03272*
X02602Y03276*
X02605Y03281*
X02607Y03288*
X02605Y03294*
X02602Y03299*
X02597Y03303*
X0259Y03304*
X02584Y03303*
X02579Y03299*
X02575Y03294*
X02575Y03291*
X02559*
Y03309*
G37*
G36*
X03744Y03277D02*
X03738Y03276D01*
X03733Y03272*
X03729Y03267*
X03728Y03261*
X03729Y03254*
X03733Y03249*
X03738Y03245*
X03744Y03244*
X03751Y03245*
X03756Y03249*
X03759Y03254*
X03761Y03261*
X03759Y03267*
X03756Y03272*
X03751Y03276*
X03744Y03277*
G37*
G36*
X0323Y03251D02*
X03224Y0325D01*
X03219Y03246*
X03215Y03241*
X03214Y03235*
X03215Y03228*
X03219Y03223*
X03224Y03219*
X0323Y03218*
X03237Y03219*
X03242Y03223*
X03245Y03228*
X03247Y03235*
X03245Y03241*
X03242Y03246*
X03237Y0325*
X0323Y03251*
G37*
G36*
X03806D02*
X038Y0325D01*
X03795Y03246*
X03791Y03241*
X0379Y03235*
X03791Y03228*
X03795Y03223*
X03797Y03222*
X03796Y03216*
X03793Y03216*
X03788Y03212*
X03784Y03207*
X03783Y03201*
X03784Y03194*
X03788Y03189*
X03793Y03185*
X03799Y03184*
X03806Y03185*
X03811Y03189*
X03814Y03194*
X03816Y03201*
X03814Y03207*
X03811Y03212*
X03809Y03214*
X0381Y03219*
X03813Y03219*
X03818Y03223*
X03821Y03228*
X03823Y03235*
X03821Y03241*
X03818Y03246*
X03813Y0325*
X03806Y03251*
G37*
G36*
X03188Y03203D02*
X03182Y03202D01*
X03177Y03198*
X03173Y03193*
X03172Y03187*
X03173Y0318*
X03177Y03175*
X03182Y03171*
X03188Y0317*
X03195Y03171*
X032Y03175*
X03204Y0318*
X03205Y03187*
X03204Y03193*
X032Y03198*
X03195Y03202*
X03188Y03203*
G37*
G36*
X01459Y03163D02*
X01453Y03162D01*
X01448Y03158*
X01444Y03153*
X01443Y03147*
X01444Y0314*
X01448Y03135*
X01453Y03131*
X01459Y0313*
X01466Y03131*
X01471Y03135*
X01474Y0314*
X01476Y03147*
X01474Y03153*
X01471Y03158*
X01466Y03162*
X01459Y03163*
G37*
G36*
X03275Y03158D02*
X03269Y03156D01*
X03264Y03153*
X0326Y03147*
X03259Y03141*
X0326Y03135*
X03264Y0313*
X03269Y03126*
X03275Y03125*
X03281Y03126*
X03287Y0313*
X0329Y03135*
X03291Y03141*
X0329Y03147*
X03287Y03153*
X03281Y03156*
X03275Y03158*
G37*
G36*
X03183Y03152D02*
X03176Y0315D01*
X03171Y03147*
X03168Y03142*
X03166Y03135*
X03168Y03129*
X03171Y03124*
X03176Y0312*
X03183Y03119*
X03189Y0312*
X03194Y03124*
X03198Y03129*
X03199Y03135*
X03198Y03142*
X03194Y03147*
X03189Y0315*
X03183Y03152*
G37*
G36*
X02559Y0323D02*
X0246D01*
Y03188*
X02456Y03187*
X0245Y03183*
X02447Y03178*
X02446Y03172*
X02447Y03166*
X0245Y0316*
X02456Y03157*
X02459Y03156*
X0246Y03151*
Y03151*
Y03091*
X02559*
Y03134*
X02595Y0317*
X02598Y03171*
X02603Y03174*
X02606Y03179*
X02608Y03186*
X02606Y03192*
X02603Y03197*
X02598Y03201*
X02591Y03202*
X02585Y03201*
X0258Y03197*
X02576Y03192*
X02575Y03186*
X02575Y03185*
X02564Y03173*
X02559Y03176*
Y0323*
G37*
G36*
X03491Y03119D02*
X03485Y03118D01*
X0348Y03114*
X03476Y03109*
X03475Y03103*
X03476Y03096*
X0348Y03091*
X03485Y03087*
X03491Y03086*
X03498Y03087*
X03503Y03091*
X03506Y03096*
X03508Y03103*
X03506Y03109*
X03503Y03114*
X03498Y03118*
X03491Y03119*
G37*
G36*
X03717Y03088D02*
X03711Y03087D01*
X03706Y03083*
X03702Y03078*
X03701Y03072*
X03702Y03065*
X03706Y0306*
X03711Y03056*
X03717Y03055*
X03724Y03056*
X03729Y0306*
X03732Y03065*
X03734Y03072*
X03732Y03078*
X03729Y03083*
X03724Y03087*
X03717Y03088*
G37*
G36*
X03368Y03066D02*
X03362Y03065D01*
X03357Y03061*
X03353Y03056*
X03352Y0305*
X03353Y03043*
X03357Y03038*
X03362Y03034*
X03368Y03033*
X03375Y03034*
X0338Y03038*
X03383Y03043*
X03385Y0305*
X03383Y03056*
X0338Y03061*
X03375Y03065*
X03368Y03066*
G37*
G36*
X03344Y03012D02*
X03338Y03011D01*
X03333Y03007*
X03329Y03002*
X03328Y02996*
X03329Y02989*
X03333Y02984*
X03338Y0298*
X03344Y02979*
X03351Y0298*
X03356Y02984*
X03359Y02989*
X03361Y02996*
X03359Y03002*
X03356Y03007*
X03351Y03011*
X03344Y03012*
G37*
G36*
X02473Y02996D02*
X02467Y02995D01*
X02464Y02993*
X02434*
X02429Y02992*
X02424Y02989*
X02416Y0298*
X02415*
X02414Y0298*
X02367*
Y02907*
X02428*
Y02956*
X02431Y02958*
X02439Y02966*
X02464*
X02467Y02964*
X02473Y02963*
X0248Y02964*
X02485Y02968*
X02488Y02973*
X0249Y0298*
X02488Y02986*
X02485Y02991*
X0248Y02995*
X02473Y02996*
G37*
G36*
X03197Y02986D02*
X03191Y02985D01*
X03186Y02981*
X03182Y02976*
X03181Y0297*
X03182Y02963*
X03186Y02958*
X03191Y02954*
X03197Y02953*
X03204Y02954*
X03209Y02958*
X03212Y02963*
X03214Y0297*
X03212Y02976*
X03209Y02981*
X03204Y02985*
X03197Y02986*
G37*
G36*
X03277Y02979D02*
X03271Y02978D01*
X03266Y02975*
X03262Y02969*
X03261Y02963*
X03262Y02957*
X03266Y02952*
X03271Y02948*
X03277Y02947*
X03283Y02948*
X03289Y02952*
X03292Y02957*
X03293Y02963*
X03292Y02969*
X03289Y02975*
X03283Y02978*
X03277Y02979*
G37*
G36*
X0337Y02904D02*
X03364Y02903D01*
X03359Y02899*
X03355Y02894*
X03354Y02888*
X03355Y02881*
X03359Y02876*
X03364Y02872*
X0337Y02871*
X03377Y02872*
X03382Y02876*
X03385Y02881*
X03387Y02888*
X03385Y02894*
X03382Y02899*
X03377Y02903*
X0337Y02904*
G37*
G36*
X02692Y02737D02*
X02686Y02736D01*
X02681Y02732*
X02677Y02727*
X02676Y02721*
X02677Y02715*
X02681Y02709*
X02686Y02706*
X02692Y02705*
X02699Y02706*
X02704Y02709*
X02707Y02715*
X02709Y02721*
X02707Y02727*
X02704Y02732*
X02699Y02736*
X02692Y02737*
G37*
G36*
X02394Y02736D02*
X02388Y02735D01*
X02383Y02732*
X02379Y02726*
X02378Y0272*
X02379Y02714*
X02383Y02708*
X02388Y02705*
X02394Y02704*
X024Y02705*
X02406Y02708*
X02409Y02714*
X02411Y0272*
X02409Y02726*
X02406Y02732*
X024Y02735*
X02394Y02736*
G37*
G36*
X02494Y02712D02*
X02488Y02711D01*
X02483Y02707*
X02479Y02702*
X02478Y02696*
X02479Y02689*
X02483Y02684*
X02488Y02681*
X02488Y02679*
Y02678*
X02488Y02675*
X02483Y02672*
X02479Y02667*
X02478Y02661*
X02479Y02654*
X02483Y02649*
X02488Y02645*
X02494Y02644*
X02501Y02645*
X02506Y02649*
X02509Y02654*
X02511Y02661*
X02509Y02667*
X02506Y02672*
X02501Y02675*
X02501Y02678*
Y02679*
X02501Y02681*
X02506Y02684*
X02509Y02689*
X02511Y02696*
X02509Y02702*
X02506Y02707*
X02501Y02711*
X02494Y02712*
G37*
G36*
X02958Y02637D02*
X02952Y02636D01*
X02947Y02632*
X02943Y02627*
X02942Y02621*
X02943Y02614*
X02947Y02609*
X02952Y02605*
X02958Y02604*
X02965Y02605*
X0297Y02609*
X02973Y02614*
X02975Y02621*
X02973Y02627*
X0297Y02632*
X02965Y02636*
X02958Y02637*
G37*
G36*
X02429D02*
X02422Y02636D01*
X02417Y02632*
X02414Y02627*
X02412Y02621*
X02414Y02614*
X02417Y02609*
X02422Y02605*
X02429Y02604*
X02435Y02605*
X0244Y02609*
X02444Y02614*
X02445Y02621*
X02444Y02627*
X0244Y02632*
X02435Y02636*
X02429Y02637*
G37*
G36*
X02252Y02629D02*
X02246Y02628D01*
X0224Y02625*
X02237Y02619*
X02236Y02613*
X02237Y02607*
X02239Y02603*
X02236Y02599*
X02231Y026*
X02225Y02599*
X0222Y02595*
X02216Y0259*
X02215Y02584*
X02216Y02577*
X0222Y02572*
X02225Y02569*
X02231Y02567*
X02237Y02569*
X02243Y02572*
X02246Y02577*
X02248Y02584*
X02246Y0259*
X02244Y02594*
X02247Y02598*
X02252Y02597*
X02258Y02598*
X02263Y02602*
X02267Y02607*
X02268Y02613*
X02267Y02619*
X02263Y02625*
X02258Y02628*
X02252Y02629*
G37*
G36*
X02821Y02617D02*
X02815Y02616D01*
X0281Y02612*
X02806Y02607*
X02805Y02601*
X02806Y02594*
X0281Y02589*
X02815Y02585*
X02821Y02584*
X02828Y02585*
X02833Y02589*
X02836Y02594*
X02838Y02601*
X02836Y02607*
X02833Y02612*
X02828Y02616*
X02821Y02617*
G37*
G36*
X03623Y02603D02*
X03617Y02602D01*
X03612Y02598*
X03608Y02593*
X03607Y02587*
X03608Y0258*
X03612Y02575*
X03617Y02571*
X03623Y0257*
X0363Y02571*
X03635Y02575*
X03638Y0258*
X0364Y02587*
X03638Y02593*
X03635Y02598*
X0363Y02602*
X03623Y02603*
G37*
G36*
X02321Y02602D02*
X02315Y02601D01*
X0231Y02597*
X02306Y02592*
X02305Y02586*
X02306Y02579*
X0231Y02574*
X02315Y0257*
X02321Y02569*
X02327Y0257*
X02333Y02574*
X02336Y02579*
X02337Y02586*
X02336Y02592*
X02333Y02597*
X02327Y02601*
X02321Y02602*
G37*
G36*
X02409Y02595D02*
X02403Y02594D01*
X02398Y0259*
X02394Y02585*
X02393Y02579*
X02394Y02572*
X02398Y02567*
X02403Y02563*
X02409Y02562*
X02416Y02563*
X02421Y02567*
X02424Y02572*
X02426Y02579*
X02424Y02585*
X02421Y0259*
X02416Y02594*
X02409Y02595*
G37*
G36*
X02586Y02585D02*
X0258Y02584D01*
X02575Y0258*
X02571Y02575*
X0257Y02569*
X02571Y02562*
X02575Y02557*
X0258Y02553*
X02586Y02552*
X02593Y02553*
X02598Y02557*
X02601Y02562*
X02603Y02569*
X02601Y02575*
X02598Y0258*
X02593Y02584*
X02586Y02585*
G37*
G36*
X02783Y02584D02*
X02777Y02583D01*
X02772Y02579*
X02768Y02574*
X02767Y02568*
X02768Y02561*
X02772Y02556*
X02777Y02552*
X02783Y02551*
X0279Y02552*
X02795Y02556*
X02798Y02561*
X028Y02568*
X02798Y02574*
X02795Y02579*
X0279Y02583*
X02783Y02584*
G37*
G36*
X02685D02*
X02679Y02583D01*
X02674Y02579*
X0267Y02574*
X02669Y02568*
X0267Y02561*
X02674Y02556*
X02679Y02552*
X02685Y02551*
X02692Y02552*
X02697Y02556*
X027Y02561*
X02702Y02568*
X027Y02574*
X02697Y02579*
X02692Y02583*
X02685Y02584*
G37*
G36*
X02881Y02582D02*
X02875Y02581D01*
X0287Y02577*
X02866Y02572*
X02865Y02566*
X02866Y02559*
X0287Y02554*
X02875Y0255*
X02881Y02549*
X02888Y0255*
X02893Y02554*
X02896Y02559*
X02898Y02566*
X02896Y02572*
X02893Y02577*
X02888Y02581*
X02881Y02582*
G37*
G36*
X02624Y02477D02*
X02618Y02476D01*
X02613Y02472*
X02609Y02467*
X02608Y02461*
X02609Y02454*
X02609Y02454*
X02606Y0245*
X02606Y02451*
X02599Y02452*
X02593Y02451*
X02588Y02447*
X02584Y02442*
X02583Y02436*
X02584Y02431*
X02583Y0243*
X02581Y02427*
X0258Y02427*
X02575Y02428*
X02569Y02427*
X02564Y02423*
X0256Y02418*
X02559Y02412*
X0256Y02405*
X02564Y024*
X02569Y02396*
X02575Y02395*
X02582Y02396*
X02587Y024*
X0259Y02405*
X02592Y02412*
X02591Y02416*
X02591Y02417*
X02594Y0242*
X02595Y0242*
X02599Y02419*
X02606Y0242*
X02611Y02424*
X02614Y02429*
X02616Y02436*
X02614Y02442*
X02614Y02442*
X02618Y02446*
X02618Y02445*
X02624Y02444*
X02631Y02445*
X02636Y02449*
X02639Y02454*
X02641Y02461*
X02639Y02467*
X02636Y02472*
X02631Y02476*
X02624Y02477*
G37*
G36*
X02272Y0248D02*
X02265Y02478D01*
X0226Y02475*
X02256Y0247*
X02255Y02463*
X02256Y02457*
X0226Y02452*
X02265Y02448*
X02272Y02447*
X02278Y02448*
X02283Y02452*
X02287Y02457*
X02288Y02463*
X02287Y0247*
X02283Y02475*
X02278Y02478*
X02272Y0248*
G37*
G36*
X02525Y02479D02*
X02519Y02478D01*
X02514Y02474*
X0251Y02469*
X02509Y02463*
X0251Y02456*
X02514Y02451*
X02519Y02447*
X02525Y02446*
X02532Y02447*
X02537Y02451*
X0254Y02456*
X02542Y02463*
X0254Y02469*
X02537Y02474*
X02532Y02478*
X02525Y02479*
G37*
G36*
X02948Y02472D02*
X02942Y02471D01*
X02937Y02467*
X02933Y02462*
X02932Y02456*
X02933Y02449*
X02937Y02444*
X02942Y0244*
X02948Y02439*
X02955Y0244*
X0296Y02444*
X02963Y02449*
X02965Y02456*
X02963Y02462*
X0296Y02467*
X02955Y02471*
X02948Y02472*
G37*
G36*
X02475D02*
X02469Y02471D01*
X02464Y02467*
X0246Y02462*
X02459Y02456*
X0246Y02449*
X02464Y02444*
X02469Y0244*
X02475Y02439*
X02482Y0244*
X02487Y02444*
X0249Y02449*
X02492Y02456*
X0249Y02462*
X02487Y02467*
X02482Y02471*
X02475Y02472*
G37*
G36*
X0299Y02457D02*
X02983Y02456D01*
X02976Y02452*
X02972Y02445*
X02971Y02438*
X02972Y02431*
X02976Y02424*
X02983Y0242*
X0299Y02419*
X02997Y0242*
X03004Y02424*
X03008Y02431*
X03009Y02438*
X03008Y02445*
X03004Y02452*
X02997Y02456*
X0299Y02457*
G37*
G36*
X02203D02*
X02195Y02456D01*
X02189Y02452*
X02185Y02445*
X02183Y02438*
X02185Y02431*
X02189Y02424*
X02195Y0242*
X02203Y02419*
X0221Y0242*
X02216Y02424*
X0222Y02431*
X02222Y02438*
X0222Y02445*
X02216Y02452*
X0221Y02456*
X02203Y02457*
G37*
G36*
X03617Y02553D02*
X03604Y02552D01*
X03592Y02548*
X0358Y02542*
X0357Y02533*
X03561Y02523*
X03555Y02512*
X03551Y02499*
X0355Y02486*
X03551Y02473*
X03555Y0246*
X03561Y02448*
X0357Y02438*
X0358Y0243*
X03592Y02424*
X03604Y0242*
X03617Y02418*
X03631Y0242*
X03643Y02424*
X03655Y0243*
X03665Y02438*
X03673Y02448*
X0368Y0246*
X03684Y02473*
X03685Y02486*
X03684Y02499*
X0368Y02512*
X03673Y02523*
X03665Y02533*
X03655Y02542*
X03643Y02548*
X03631Y02552*
X03617Y02553*
G37*
G36*
X02783Y02445D02*
X02777Y02444D01*
X02772Y0244*
X02768Y02435*
X02767Y02429*
X02768Y02422*
X02772Y02417*
X02777Y02413*
X02783Y02412*
X0279Y02413*
X02795Y02417*
X02798Y02422*
X028Y02429*
X02798Y02435*
X02795Y0244*
X0279Y02444*
X02783Y02445*
G37*
G36*
X02894Y02447D02*
X02888Y02446D01*
X02883Y02442*
X02879Y02437*
X02878Y02431*
X02879Y02424*
X02883Y02419*
X02888Y02415*
X02894Y02414*
X02901Y02415*
X02902Y02417*
X02909Y02416*
X02914Y02412*
X0292Y02411*
X02927Y02412*
X02932Y02416*
X02935Y02421*
X02937Y02428*
X02935Y02434*
X02932Y02439*
X02927Y02443*
X0292Y02444*
X02914Y02443*
X02909Y02439*
X02908*
X02906Y02442*
X02901Y02446*
X02894Y02447*
G37*
G36*
X02488Y02429D02*
X02482Y02428D01*
X02477Y02424*
X02473Y02419*
X02472Y02413*
X02473Y02406*
X02477Y02401*
X02482Y02397*
X02488Y02396*
X02495Y02397*
X025Y02401*
X02503Y02406*
X02505Y02413*
X02503Y02419*
X025Y02424*
X02495Y02428*
X02488Y02429*
G37*
G36*
X02404Y02428D02*
X02398Y02427D01*
X02393Y02423*
X02389Y02418*
X02388Y02412*
X02389Y02405*
X02393Y024*
X02398Y02396*
X02404Y02395*
X02411Y02396*
X02416Y024*
X02419Y02405*
X02421Y02412*
X02419Y02418*
X02416Y02423*
X02411Y02427*
X02404Y02428*
G37*
G36*
X03498Y02357D02*
X03492Y02356D01*
X03487Y02352*
X03483Y02347*
X03482Y02341*
X03483Y02334*
X03487Y02329*
X03492Y02325*
X03498Y02324*
X03505Y02325*
X0351Y02329*
X03513Y02334*
X03515Y02341*
X03513Y02347*
X0351Y02352*
X03505Y02356*
X03498Y02357*
G37*
G36*
X02475Y02307D02*
X02469Y02306D01*
X02464Y02302*
X0246Y02297*
X02455Y02297*
X0245Y02298*
X02444Y02297*
X02439Y02293*
X02435Y02288*
X02434Y02282*
X02435Y02275*
X02439Y0227*
X02444Y02266*
X0245Y02265*
X02457Y02266*
X02462Y0227*
X02465Y02275*
X0247Y02275*
X02475Y02274*
X02482Y02275*
X02487Y02279*
X0249Y02284*
X02492Y02291*
X0249Y02297*
X02487Y02302*
X02482Y02306*
X02475Y02307*
G37*
G36*
X02803Y02323D02*
X02797Y02322D01*
X02792Y02318*
X02788Y02313*
X02787Y02307*
X02788Y023*
X02792Y02295*
X02797Y02291*
X02803Y0229*
X0281Y02291*
X02815Y02295*
X02818Y023*
X0282Y02307*
X02818Y02313*
X02815Y02318*
X0281Y02322*
X02803Y02323*
G37*
G36*
X02685Y02327D02*
X02679Y02326D01*
X02674Y02322*
X0267Y02317*
X02669Y02311*
X02668Y0231*
X02666Y02308*
X02665Y02307*
X02659Y02306*
X02654Y02302*
X0265Y02297*
X02649Y02291*
X02648Y02289*
X02645Y0229*
X02639Y02289*
X02634Y02285*
X0263Y0228*
X02629Y02274*
X0263Y02267*
X02634Y02262*
X02639Y02258*
X02645Y02257*
X02652Y02258*
X02657Y02262*
X0266Y02267*
X02662Y02274*
X02663Y02275*
X02665Y02274*
X02672Y02275*
X02677Y02279*
X0268Y02284*
X02681Y02289*
X02686Y02289*
X02687Y02282*
X02691Y02277*
X02696Y02273*
X02702Y02272*
X02709Y02273*
X02714Y02277*
X02716Y0228*
X0272Y02277*
X02726Y02276*
X02733Y02277*
X02738Y02281*
X02741Y02286*
X02743Y02293*
X02741Y02299*
X02738Y02304*
X02733Y02308*
X02726Y02309*
X0272Y02308*
X02715Y02304*
X02713Y02301*
X02709Y02304*
X02706Y02304*
X02701Y02309*
X02702Y02311*
X027Y02317*
X02697Y02322*
X02692Y02326*
X02685Y02327*
G37*
G36*
X02871Y02313D02*
X02865Y02312D01*
X0286Y02308*
X02856Y02303*
X02855Y02297*
X02856Y0229*
X0286Y02285*
X02865Y02281*
X02871Y0228*
X02878Y02281*
X02883Y02285*
X02886Y0229*
X02888Y02297*
X02886Y02303*
X02883Y02308*
X02878Y02312*
X02871Y02313*
G37*
G36*
X02985Y02303D02*
X02979Y02302D01*
X02974Y02298*
X0297Y02293*
X02969Y02287*
X0297Y0228*
X02974Y02275*
X02979Y02271*
X02985Y0227*
X02992Y02271*
X02997Y02275*
X03Y0228*
X03002Y02287*
X03Y02293*
X02997Y02298*
X02992Y02302*
X02985Y02303*
G37*
G36*
X02942Y02302D02*
X02936Y02301D01*
X02931Y02297*
X02927Y02292*
X02926Y02286*
X02927Y02279*
X02931Y02274*
X02936Y0227*
X02942Y02269*
X02949Y0227*
X02954Y02274*
X02957Y02279*
X02959Y02286*
X02957Y02292*
X02954Y02297*
X02949Y02301*
X02942Y02302*
G37*
G36*
X02409Y0233D02*
X02403Y02329D01*
X02398Y02325*
X02394Y0232*
X02393Y02314*
X02394Y02307*
X02398Y02302*
X02399Y02301*
Y02295*
X02398Y02294*
X02394Y02289*
X02393Y02283*
X02394Y02276*
X02398Y02271*
X02403Y02267*
X02409Y02266*
X02416Y02267*
X02421Y02271*
X02424Y02276*
X02426Y02283*
X02424Y02289*
X02421Y02294*
X02419Y02295*
Y02301*
X02421Y02302*
X02424Y02307*
X02426Y02314*
X02424Y0232*
X02421Y02325*
X02416Y02329*
X02409Y0233*
G37*
G36*
X02581Y02324D02*
X02575Y02323D01*
X0257Y02319*
X02566Y02314*
X02565Y02308*
X02566Y02301*
X02568Y02298*
X02568Y02292*
X02564Y02287*
X02563Y02281*
X02564Y02274*
X02568Y02269*
X02573Y02265*
X02579Y02264*
X02586Y02265*
X02591Y02269*
X02594Y02274*
X02596Y02281*
X02594Y02287*
X02592Y0229*
X02593Y02296*
X02596Y02301*
X02598Y02308*
X02596Y02314*
X02593Y02319*
X02588Y02323*
X02581Y02324*
G37*
G36*
X02253Y02295D02*
X02247Y02294D01*
X02242Y0229*
X02238Y02285*
X02237Y02279*
X02238Y02272*
X02242Y02267*
X02247Y02263*
X02253Y02262*
X0226Y02263*
X02265Y02267*
X02268Y02272*
X0227Y02279*
X02268Y02285*
X02265Y0229*
X0226Y02294*
X02253Y02295*
G37*
G36*
X03342Y02279D02*
X03336Y02278D01*
X03331Y02274*
X03327Y02269*
X03326Y02263*
X03327Y02256*
X03331Y02251*
X03336Y02247*
X03342Y02246*
X03349Y02247*
X03354Y02251*
X03357Y02256*
X03359Y02263*
X03357Y02269*
X03354Y02274*
X03349Y02278*
X03342Y02279*
G37*
G36*
X02841D02*
X02835Y02278D01*
X0283Y02274*
X02826Y02269*
X02825Y02263*
X02826Y02256*
X0283Y02251*
X02835Y02247*
X02841Y02246*
X02848Y02247*
X02853Y02251*
X02856Y02256*
X02858Y02263*
X02856Y02269*
X02853Y02274*
X02848Y02278*
X02841Y02279*
G37*
G36*
X02499Y02252D02*
X02493Y02251D01*
X02488Y02247*
X02484Y02242*
X02483Y02236*
X02484Y02229*
X02488Y02224*
X02493Y0222*
X02499Y02219*
X02506Y0222*
X02511Y02224*
X02514Y02229*
X02516Y02236*
X02514Y02242*
X02511Y02247*
X02506Y02251*
X02499Y02252*
G37*
G36*
X0233Y02231D02*
X02324Y0223D01*
X02319Y02226*
X02315Y02221*
X02314Y02215*
X02315Y02208*
X02319Y02203*
X02324Y02199*
X0233Y02198*
X02337Y02199*
X02342Y02203*
X02345Y02208*
X02347Y02215*
X02345Y02221*
X02342Y02226*
X02337Y0223*
X0233Y02231*
G37*
G36*
X03571Y02116D02*
X03564Y02114D01*
X03558Y0211*
X03554Y02104*
X03552Y02097*
X03554Y02089*
X03558Y02083*
X03564Y02079*
X03571Y02077*
X03579Y02079*
X03585Y02083*
X03589Y02089*
X0359Y02097*
X03589Y02104*
X03585Y0211*
X03579Y02114*
X03571Y02116*
G37*
G36*
X03719Y02012D02*
X03713Y02011D01*
X03708Y02007*
X03704Y02002*
X03703Y01996*
X03704Y01989*
X03708Y01984*
X03713Y0198*
X03719Y01979*
X03726Y0198*
X03731Y01984*
X03734Y01989*
X03736Y01996*
X03734Y02002*
X03731Y02007*
X03726Y02011*
X03719Y02012*
G37*
G36*
X03554Y02007D02*
X03548Y02006D01*
X03543Y02002*
X03539Y01997*
X03538Y01991*
X03539Y01984*
X03543Y01979*
X03548Y01975*
X03554Y01974*
X03561Y01975*
X03566Y01979*
X03569Y01984*
X03571Y01991*
X03569Y01997*
X03566Y02002*
X03561Y02006*
X03554Y02007*
G37*
G36*
X03298Y01987D02*
X03292Y01986D01*
X03287Y01982*
X03283Y01977*
X03282Y01971*
X03283Y01964*
X03287Y01959*
X03292Y01955*
X03298Y01954*
X03305Y01955*
X0331Y01959*
X03313Y01964*
X03315Y01971*
X03313Y01977*
X0331Y01982*
X03305Y01986*
X03298Y01987*
G37*
G36*
X03554Y01957D02*
X03548Y01956D01*
X03543Y01952*
X03539Y01947*
X03538Y01941*
X03539Y01934*
X03543Y01929*
X03548Y01925*
X03554Y01924*
X03561Y01925*
X03566Y01929*
X03569Y01934*
X03571Y01941*
X03569Y01947*
X03566Y01952*
X03561Y01956*
X03554Y01957*
G37*
G36*
X03719Y01937D02*
X03713Y01936D01*
X03708Y01932*
X03704Y01927*
X03703Y01921*
X03704Y01914*
X03708Y01909*
X03713Y01905*
X03719Y01904*
X03726Y01905*
X03731Y01909*
X03734Y01914*
X03736Y01921*
X03734Y01927*
X03731Y01932*
X03726Y01936*
X03719Y01937*
G37*
G36*
X03554Y01907D02*
X03548Y01906D01*
X03543Y01902*
X03539Y01897*
X03538Y01891*
X03539Y01884*
X03543Y01879*
X03548Y01875*
X03554Y01874*
X03561Y01875*
X03566Y01879*
X03569Y01884*
X03571Y01891*
X03569Y01897*
X03566Y01902*
X03561Y01906*
X03554Y01907*
G37*
G36*
X03392Y01887D02*
X03386Y01886D01*
X03381Y01882*
X03377Y01877*
X03376Y01871*
X03377Y01864*
X03381Y01859*
X03386Y01855*
X03392Y01854*
X03399Y01855*
X03404Y01859*
X03407Y01864*
X03409Y01871*
X03407Y01877*
X03404Y01882*
X03399Y01886*
X03392Y01887*
G37*
G36*
X03439Y01887D02*
X03433Y01886D01*
X03427Y01882*
X03424Y01877*
X03422Y0187*
X03424Y01864*
X03427Y01859*
X03433Y01855*
X03439Y01854*
X03445Y01855*
X0345Y01859*
X03454Y01864*
X03455Y0187*
X03454Y01877*
X0345Y01882*
X03445Y01886*
X03439Y01887*
G37*
G36*
X03554Y01857D02*
X03548Y01856D01*
X03543Y01852*
X03539Y01847*
X03538Y01841*
X03539Y01834*
X03543Y01829*
X03548Y01825*
X03554Y01824*
X03561Y01825*
X03566Y01829*
X03569Y01834*
X03571Y01841*
X03569Y01847*
X03566Y01852*
X03561Y01856*
X03554Y01857*
G37*
G36*
X03804Y01856D02*
X03798Y01855D01*
X03793Y01851*
X03789Y01846*
X03788Y0184*
X03789Y01833*
X03793Y01828*
X03798Y01824*
X03804Y01823*
X03811Y01824*
X03816Y01828*
X03819Y01833*
X03821Y0184*
X03819Y01846*
X03816Y01851*
X03811Y01855*
X03804Y01856*
G37*
G36*
X06685Y01844D02*
X06679Y01843D01*
X06674Y01839*
X0667Y01834*
X06669Y01828*
X0667Y01821*
X06674Y01816*
X06679Y01812*
X06685Y01811*
X06692Y01812*
X06697Y01816*
X067Y01821*
X06702Y01828*
X067Y01834*
X06697Y01839*
X06692Y01843*
X06685Y01844*
G37*
G36*
X03329Y01842D02*
X03322Y01841D01*
X03317Y01837*
X03314Y01832*
X03312Y01826*
X03314Y01819*
X03317Y01814*
X03322Y0181*
X03329Y01809*
X03335Y0181*
X0334Y01814*
X03344Y01819*
X03345Y01826*
X03344Y01832*
X0334Y01837*
X03335Y01841*
X03329Y01842*
G37*
G36*
X03944Y01832D02*
X03938Y01831D01*
X03933Y01827*
X03929Y01822*
X03928Y01816*
X03929Y01809*
X03933Y01804*
X03938Y018*
X03944Y01799*
X03951Y018*
X03956Y01804*
X03959Y01809*
X03961Y01816*
X03959Y01822*
X03956Y01827*
X03951Y01831*
X03944Y01832*
G37*
G36*
X03056Y01828D02*
X0305Y01826D01*
X03045Y01823*
X03041Y01818*
X0304Y01811*
X03041Y01805*
X03045Y018*
X0305Y01796*
X03056Y01795*
X03063Y01796*
X03068Y018*
X03071Y01805*
X03073Y01811*
X03071Y01818*
X03068Y01823*
X03063Y01826*
X03056Y01828*
G37*
G36*
X03414Y01821D02*
X03408Y0182D01*
X03402Y01816*
X03399Y01811*
X03398Y01805*
X03399Y01798*
X03402Y01793*
X03408Y01789*
X03414Y01788*
X0342Y01789*
X03426Y01793*
X03429Y01798*
X0343Y01805*
X03429Y01811*
X03426Y01816*
X0342Y0182*
X03414Y01821*
G37*
G36*
X04064Y01812D02*
X04058Y01811D01*
X04053Y01807*
X04049Y01802*
X04048Y01796*
X04049Y01789*
X04053Y01784*
X04058Y0178*
X04064Y01779*
X04071Y0178*
X04076Y01784*
X04079Y01789*
X04081Y01796*
X04079Y01802*
X04076Y01807*
X04071Y01811*
X04064Y01812*
G37*
G36*
X06601Y01793D02*
X06595Y01792D01*
X0659Y01788*
X06586Y01783*
X06585Y01777*
X06586Y0177*
X0659Y01765*
X06595Y01761*
X06601Y0176*
X06608Y01761*
X06613Y01765*
X06616Y0177*
X06618Y01777*
X06616Y01783*
X06613Y01788*
X06608Y01792*
X06601Y01793*
G37*
G36*
X03719Y01782D02*
X03713Y01781D01*
X03708Y01777*
X03704Y01772*
X03703Y01766*
X03704Y01759*
X03708Y01754*
X03713Y0175*
X03719Y01749*
X03726Y0175*
X03731Y01754*
X03734Y01759*
X03736Y01766*
X03734Y01772*
X03731Y01777*
X03726Y01781*
X03719Y01782*
G37*
G36*
X04134Y01767D02*
X04128Y01766D01*
X04123Y01762*
X04119Y01757*
X04118Y01751*
X04119Y01744*
X04123Y01739*
X04128Y01735*
X04134Y01734*
X04141Y01735*
X04146Y01739*
X04149Y01744*
X04151Y01751*
X04149Y01757*
X04146Y01762*
X04141Y01766*
X04134Y01767*
G37*
G36*
X06602Y01738D02*
X06596Y01737D01*
X06591Y01733*
X06587Y01728*
X06586Y01722*
X06587Y01715*
X06591Y0171*
X06596Y01706*
X06602Y01705*
X06609Y01706*
X06614Y0171*
X06617Y01715*
X06619Y01722*
X06617Y01728*
X06614Y01733*
X06609Y01737*
X06602Y01738*
G37*
G36*
X03197Y0173D02*
X03191Y01729D01*
X03185Y01725*
X03182Y0172*
X0318Y01714*
X03182Y01707*
X03185Y01702*
X03191Y01698*
X03197Y01697*
X03203Y01698*
X03208Y01702*
X03212Y01707*
X03213Y01714*
X03212Y0172*
X03208Y01725*
X03203Y01729*
X03197Y0173*
G37*
G36*
X0341Y01729D02*
X03404Y01728D01*
X03399Y01725*
X03395Y01719*
X03394Y01713*
X03395Y01707*
X03399Y01702*
X03404Y01698*
X0341Y01697*
X03417Y01698*
X03422Y01702*
X03425Y01707*
X03427Y01713*
X03425Y01719*
X03422Y01725*
X03417Y01728*
X0341Y01729*
G37*
G36*
X03718Y01729D02*
X03712Y01728D01*
X03707Y01724*
X03703Y01719*
X03702Y01713*
X03703Y01706*
X03707Y01701*
X03712Y01697*
X03718Y01696*
X03725Y01697*
X0373Y01701*
X03733Y01706*
X03735Y01713*
X03733Y01719*
X0373Y01724*
X03725Y01728*
X03718Y01729*
G37*
G36*
X03996Y01727D02*
X0399Y01726D01*
X03985Y01722*
X03981Y01717*
X0398Y01711*
X03981Y01704*
X03985Y01699*
X0399Y01695*
X03996Y01694*
X04003Y01695*
X04008Y01699*
X04011Y01704*
X04013Y01711*
X04011Y01717*
X04008Y01722*
X04003Y01726*
X03996Y01727*
G37*
G36*
X03589D02*
X03583Y01726D01*
X03578Y01722*
X03574Y01717*
X03573Y01711*
X03574Y01704*
X03578Y01699*
X03583Y01695*
X03589Y01694*
X03596Y01695*
X03601Y01699*
X03604Y01704*
X03606Y01711*
X03604Y01717*
X03601Y01722*
X03596Y01726*
X03589Y01727*
G37*
G36*
X03803Y01707D02*
X03797Y01706D01*
X03792Y01702*
X03788Y01697*
X03787Y01691*
X03788Y01684*
X03792Y01679*
X03797Y01675*
X03803Y01674*
X0381Y01675*
X03815Y01679*
X03818Y01684*
X0382Y01691*
X03818Y01697*
X03815Y01702*
X0381Y01706*
X03803Y01707*
G37*
G36*
X03724Y01691D02*
X03718Y0169D01*
X03713Y01686*
X03709Y01681*
X03708Y01675*
X03709Y01668*
X03713Y01663*
X03718Y01659*
X03724Y01658*
X03731Y01659*
X03736Y01663*
X03739Y01668*
X03741Y01675*
X03739Y01681*
X03736Y01686*
X03731Y0169*
X03724Y01691*
G37*
G36*
X06602Y01688D02*
X06596Y01687D01*
X06591Y01683*
X06587Y01678*
X06586Y01672*
X06587Y01665*
X06591Y0166*
X06596Y01656*
X06602Y01655*
X06609Y01656*
X06614Y0166*
X06617Y01665*
X06619Y01672*
X06617Y01678*
X06614Y01683*
X06609Y01687*
X06602Y01688*
G37*
G36*
X03968Y01687D02*
X03962Y01686D01*
X03957Y01682*
X03953Y01677*
X03952Y01671*
X03953Y01664*
X03957Y01659*
X03962Y01655*
X03968Y01654*
X03975Y01655*
X0398Y01659*
X03983Y01664*
X03985Y01671*
X03983Y01677*
X0398Y01682*
X03975Y01686*
X03968Y01687*
G37*
G36*
X03773Y01682D02*
X03767Y01681D01*
X03762Y01677*
X03758Y01672*
X03757Y01666*
X03758Y01659*
X03762Y01654*
X03767Y01651*
X03773Y01649*
X0378Y01651*
X03785Y01654*
X03788Y01659*
X0379Y01666*
X03788Y01672*
X03785Y01677*
X0378Y01681*
X03773Y01682*
G37*
G36*
X0359Y01678D02*
X03584Y01677D01*
X03579Y01673*
X03575Y01668*
X03574Y01662*
X03575Y01655*
X03579Y0165*
X03584Y01646*
X0359Y01645*
X03597Y01646*
X03602Y0165*
X03605Y01655*
X03607Y01662*
X03605Y01668*
X03602Y01673*
X03597Y01677*
X0359Y01678*
G37*
G36*
X03224Y01677D02*
X03218Y01676D01*
X03213Y01672*
X03209Y01667*
X03208Y01661*
X03209Y01655*
X03213Y01649*
X03218Y01646*
X03224Y01645*
X03231Y01646*
X03235Y01649*
X03239Y01649*
X03241Y01649*
X03246Y01645*
X03252Y01644*
X03259Y01645*
X03264Y01649*
X03267Y01654*
X03269Y01661*
X03267Y01667*
X03264Y01672*
X03259Y01676*
X03252Y01677*
X03246Y01676*
X03242Y01673*
X03238Y01672*
X03235Y01673*
X03231Y01676*
X03224Y01677*
G37*
G36*
X05578Y01735D02*
X05566Y01734D01*
X05555Y01729*
X05545Y01722*
X05538Y01712*
X05533Y01701*
X05532Y01689*
X05533Y01677*
X05538Y01666*
X05545Y01657*
X05555Y0165*
X05566Y01645*
X05578Y01643*
X0559Y01645*
X05601Y0165*
X0561Y01657*
X05617Y01666*
X05622Y01677*
X05624Y01689*
X05622Y01701*
X05617Y01712*
X0561Y01722*
X05601Y01729*
X0559Y01734*
X05578Y01735*
G37*
G36*
X06602Y01628D02*
X06596Y01627D01*
X06591Y01623*
X06587Y01618*
X06586Y01612*
X06587Y01605*
X06591Y016*
X06596Y01596*
X06602Y01595*
X06609Y01596*
X06614Y016*
X06617Y01605*
X06619Y01612*
X06617Y01618*
X06614Y01623*
X06609Y01627*
X06602Y01628*
G37*
G36*
X04131Y01702D02*
X04125Y01701D01*
X0412Y01697*
X04116Y01692*
X04115Y01686*
X04116Y01679*
X0412Y01674*
X04125Y0167*
X04127Y0167*
X04127Y01669*
X04127Y01665*
X04123Y01662*
X04119Y01657*
X04118Y01651*
X04119Y01644*
X04123Y01639*
X04128Y01635*
X04133Y01634*
X04135Y01631*
X04136Y01629*
X04136Y01629*
X04134Y01623*
X04136Y01617*
X04139Y01612*
X04145Y01608*
X04151Y01607*
X04157Y01608*
X04161Y01611*
X04164Y01607*
X04164Y01607*
X04163Y01601*
X04164Y01594*
X04168Y01589*
X04173Y01585*
X04179Y01584*
X04186Y01585*
X04191Y01589*
X04194Y01594*
X04196Y01601*
X04194Y01607*
X04191Y01612*
X04186Y01616*
X04179Y01617*
X04173Y01616*
X04169Y01613*
X04166Y01617*
X04166Y01617*
X04167Y01623*
X04166Y01629*
X04162Y01635*
X04157Y01638*
X04152Y01639*
X0415Y01643*
X04149Y01644*
X04149Y01644*
X04151Y01651*
X04149Y01657*
X04146Y01662*
X04141Y01666*
X04139Y01666*
X04139Y01667*
X04139Y01671*
X04143Y01674*
X04146Y01679*
X04148Y01686*
X04146Y01692*
X04143Y01697*
X04138Y01701*
X04131Y01702*
G37*
G36*
X03413Y01589D02*
X03407Y01588D01*
X03402Y01584*
X03398Y01579*
X03397Y01573*
X03398Y01566*
X03402Y01561*
X03407Y01557*
X03413Y01556*
X0342Y01557*
X03425Y01561*
X03428Y01566*
X0343Y01573*
X03428Y01579*
X03425Y01584*
X0342Y01588*
X03413Y01589*
G37*
G36*
X03894Y01582D02*
X03888Y01581D01*
X03883Y01577*
X03879Y01572*
X03878Y01566*
X03879Y01559*
X03883Y01554*
X03888Y0155*
X03894Y01549*
X03901Y0155*
X03906Y01554*
X03909Y01559*
X03911Y01566*
X03909Y01572*
X03906Y01577*
X03901Y01581*
X03894Y01582*
G37*
G36*
X03969Y01568D02*
X03963Y01567D01*
X03958Y01563*
X03954Y01558*
X03953Y01552*
X03954Y01545*
X03958Y0154*
X03963Y01536*
X03969Y01535*
X03976Y01536*
X03978Y01538*
X03983Y01539*
X03985Y01537*
X03988Y01535*
X03994Y01534*
X04001Y01535*
X04006Y01539*
X04009Y01544*
X04011Y01551*
X04009Y01557*
X04006Y01562*
X04001Y01566*
X03994Y01567*
X03988Y01566*
X03983Y01562*
X03982*
X03981Y01563*
X03976Y01567*
X03969Y01568*
G37*
G36*
X04034Y01562D02*
X04028Y01561D01*
X04023Y01557*
X04019Y01552*
X04018Y01546*
X04019Y01539*
X04023Y01534*
X04028Y0153*
X04034Y01529*
X04041Y0153*
X04046Y01534*
X04049Y01539*
X04051Y01546*
X04049Y01552*
X04046Y01557*
X04041Y01561*
X04034Y01562*
G37*
G36*
X03924Y01552D02*
X03918Y01551D01*
X03913Y01547*
X03909Y01542*
X03908Y01536*
X03909Y01529*
X03913Y01524*
X03918Y0152*
X03924Y01519*
X03931Y0152*
X03936Y01524*
X03939Y01529*
X03941Y01536*
X03939Y01542*
X03936Y01547*
X03931Y01551*
X03924Y01552*
G37*
G36*
X02894Y01577D02*
X02888Y01576D01*
X02883Y01572*
X02879Y01567*
X02878Y01561*
X02879Y01554*
X02883Y01549*
X02888Y01545*
X02894Y01544*
X02901Y01545*
X02901Y01546*
X02904Y01542*
X02904Y01542*
X02903Y01536*
X02904Y01529*
X02908Y01524*
X02913Y0152*
X02919Y01519*
X02926Y0152*
X02931Y01524*
X02934Y01529*
X02936Y01536*
X02934Y01542*
X02931Y01547*
X02926Y01551*
X02919Y01552*
X02913Y01551*
X02913Y0155*
X02909Y01554*
X02909Y01554*
X02911Y01561*
X02909Y01567*
X02906Y01572*
X02901Y01576*
X02894Y01577*
G37*
G36*
X06548Y01547D02*
X06542Y01546D01*
X06537Y01542*
X06533Y01537*
X06532Y01531*
X06533Y01524*
X06537Y01519*
X06542Y01515*
X06548Y01514*
X06555Y01515*
X0656Y01519*
X06563Y01524*
X06565Y01531*
X06563Y01537*
X0656Y01542*
X06555Y01546*
X06548Y01547*
G37*
G36*
X03594Y0153D02*
X03588Y01529D01*
X03583Y01525*
X03579Y0152*
X03578Y01514*
X03579Y01507*
X03583Y01502*
X03588Y01498*
X03594Y01497*
X03601Y01498*
X03606Y01502*
X03609Y01507*
X03611Y01514*
X03609Y0152*
X03606Y01525*
X03601Y01529*
X03594Y0153*
G37*
G36*
X04064Y01527D02*
X04058Y01526D01*
X04053Y01522*
X04049Y01517*
X04048Y01511*
X04049Y01504*
X04053Y01499*
X04058Y01495*
X04064Y01494*
X04071Y01495*
X04076Y01499*
X04079Y01504*
X04081Y01511*
X04079Y01517*
X04076Y01522*
X04071Y01526*
X04064Y01527*
G37*
G36*
X03864D02*
X03858Y01526D01*
X03853Y01522*
X03849Y01517*
X03848Y01511*
X03849Y01504*
X03853Y01499*
X03858Y01495*
X03864Y01494*
X03871Y01495*
X03876Y01499*
X03879Y01504*
X03881Y01511*
X03879Y01517*
X03876Y01522*
X03871Y01526*
X03864Y01527*
G37*
G36*
X03834Y01497D02*
X03828Y01496D01*
X03823Y01492*
X03819Y01487*
X03818Y01481*
X03819Y01474*
X03823Y01469*
X03828Y01465*
X03834Y01464*
X03841Y01465*
X03846Y01469*
X03849Y01474*
X03851Y01481*
X03849Y01487*
X03846Y01492*
X03841Y01496*
X03834Y01497*
G37*
G36*
X03406Y01477D02*
X034Y01476D01*
X03395Y01472*
X03391Y01467*
X0339Y01461*
X03391Y01454*
X03395Y01449*
X034Y01445*
X03406Y01444*
X03413Y01445*
X03418Y01449*
X03421Y01454*
X03423Y01461*
X03421Y01467*
X03418Y01472*
X03413Y01476*
X03406Y01477*
G37*
G36*
X03732Y01434D02*
X03726Y01433D01*
X03721Y01429*
X03717Y01424*
X03716Y01418*
X03717Y01411*
X03721Y01406*
X03726Y01402*
X03732Y01401*
X03739Y01402*
X03744Y01406*
X03747Y01411*
X03749Y01418*
X03747Y01424*
X03744Y01429*
X03739Y01433*
X03732Y01434*
G37*
G36*
X03407Y01427D02*
X03401Y01426D01*
X03395Y01422*
X03392Y01417*
X0339Y01411*
X03392Y01405*
X03395Y014*
X03391Y01397*
X03386Y01401*
X03379Y01402*
X03373Y01401*
X03368Y01397*
X03364Y01392*
X03363Y01386*
X03364Y01379*
X03368Y01374*
X03373Y0137*
X03379Y01369*
X03385Y0137*
X03388Y01368*
X03389Y01367*
X03388Y01363*
X03389Y01357*
X03392Y01353*
X03392Y01352*
X03389Y01349*
X03388Y01349*
X03386Y01351*
X03379Y01352*
X03373Y01351*
X03368Y01347*
X03364Y01342*
X03363Y01336*
X03364Y01329*
X03368Y01324*
X03373Y0132*
X03379Y01319*
X03386Y0132*
X03391Y01324*
X03394Y01329*
X03396Y01336*
X03394Y01342*
X03392Y01345*
X03392Y01346*
X03395Y0135*
X03396Y01349*
X03398Y01348*
X03404Y01347*
X03411Y01348*
X03416Y01351*
X03419Y01357*
X03421Y01363*
X03419Y01369*
X03416Y01374*
X03411Y01378*
X03404Y01379*
X03399Y01378*
X03396Y0138*
X03395Y01382*
X03396Y01386*
X03394Y01392*
X03391Y01396*
X03395Y01399*
X03401Y01396*
X03407Y01395*
X03413Y01396*
X03418Y01399*
X03422Y01405*
X03423Y01411*
X03422Y01417*
X03418Y01422*
X03413Y01426*
X03407Y01427*
G37*
G36*
X03549Y01457D02*
X03543Y01456D01*
X03538Y01452*
X03534Y01447*
X03533Y01441*
X03534Y01434*
X03538Y01429*
Y01424*
X03534Y01419*
X03533Y01413*
X03534Y01406*
X03538Y01401*
X03543Y01397*
X03549Y01396*
X03556Y01397*
X03561Y01401*
X03564Y01406*
X03566Y01413*
X03564Y01419*
X03561Y01424*
Y01429*
X03564Y01434*
X03566Y01441*
X03564Y01447*
X03561Y01452*
X03556Y01456*
X03549Y01457*
G37*
G36*
X03571Y01328D02*
X03564Y01327D01*
X03558Y01323*
X03554Y01317*
X03552Y01309*
X03554Y01302*
X03558Y01296*
X03564Y01292*
X03571Y0129*
X03579Y01292*
X03585Y01296*
X03589Y01302*
X0359Y01309*
X03589Y01317*
X03585Y01323*
X03579Y01327*
X03571Y01328*
G37*
G36*
X04366Y01045D02*
X04289D01*
Y00968*
X04366*
Y01045*
G37*
G36*
X05327Y01046D02*
X05317Y01045D01*
X05308Y01041*
X053Y01034*
X05294Y01026*
X0529Y01017*
X05288Y01007*
X0529Y00997*
X05294Y00988*
X053Y0098*
X05308Y00973*
X05317Y00969*
X05327Y00968*
X05337Y00969*
X05347Y00973*
X05355Y0098*
X05361Y00988*
X05365Y00997*
X05366Y01007*
X05365Y01017*
X05361Y01026*
X05355Y01034*
X05347Y01041*
X05337Y01045*
X05327Y01046*
G37*
G36*
X05127D02*
X05117Y01045D01*
X05108Y01041*
X051Y01034*
X05094Y01026*
X0509Y01017*
X05088Y01007*
X0509Y00997*
X05094Y00988*
X051Y0098*
X05108Y00973*
X05117Y00969*
X05127Y00968*
X05137Y00969*
X05147Y00973*
X05155Y0098*
X05161Y00988*
X05165Y00997*
X05166Y01007*
X05165Y01017*
X05161Y01026*
X05155Y01034*
X05147Y01041*
X05137Y01045*
X05127Y01046*
G37*
G36*
X04927D02*
X04917Y01045D01*
X04908Y01041*
X049Y01034*
X04894Y01026*
X0489Y01017*
X04888Y01007*
X0489Y00997*
X04894Y00988*
X049Y0098*
X04908Y00973*
X04917Y00969*
X04927Y00968*
X04937Y00969*
X04947Y00973*
X04955Y0098*
X04961Y00988*
X04965Y00997*
X04966Y01007*
X04965Y01017*
X04961Y01026*
X04955Y01034*
X04947Y01041*
X04937Y01045*
X04927Y01046*
G37*
G36*
X03617Y00983D02*
X03604Y00982D01*
X03592Y00978*
X0358Y00972*
X0357Y00963*
X03561Y00953*
X03555Y00942*
X03551Y00929*
X0355Y00916*
X03551Y00903*
X03555Y0089*
X03561Y00878*
X0357Y00868*
X0358Y0086*
X03592Y00854*
X03604Y0085*
X03617Y00848*
X03631Y0085*
X03643Y00854*
X03655Y0086*
X03665Y00868*
X03673Y00878*
X0368Y0089*
X03684Y00903*
X03685Y00916*
X03684Y00929*
X0368Y00942*
X03673Y00953*
X03665Y00963*
X03655Y00972*
X03643Y00978*
X03631Y00982*
X03617Y00983*
G37*
G36*
X05578Y00936D02*
X05566Y00934D01*
X05555Y0093*
X05545Y00923*
X05538Y00913*
X05533Y00902*
X05532Y0089*
X05533Y00878*
X05538Y00867*
X05545Y00858*
X05555Y0085*
X05566Y00846*
X05578Y00844*
X0559Y00846*
X05601Y0085*
X0561Y00858*
X05617Y00867*
X05622Y00878*
X05624Y0089*
X05622Y00902*
X05617Y00913*
X0561Y00923*
X05601Y0093*
X0559Y00934*
X05578Y00936*
G37*
G36*
X03395Y04238D02*
X03389Y04237D01*
X03384Y04233*
X0338Y04228*
X03379Y04222*
X0338Y04215*
X03384Y0421*
X03389Y04206*
X03395Y04205*
X03402Y04206*
X03407Y0421*
X0341Y04215*
X03412Y04222*
X0341Y04228*
X03407Y04233*
X03402Y04237*
X03395Y04238*
G37*
G36*
X02888Y04237D02*
X02882Y04236D01*
X02877Y04232*
X02873Y04227*
X02872Y04221*
X02873Y04214*
X02877Y04209*
X02882Y04205*
X02888Y04204*
X02895Y04205*
X029Y04209*
X02903Y04214*
X02905Y04221*
X02903Y04227*
X029Y04232*
X02895Y04236*
X02888Y04237*
G37*
G36*
X0229Y04233D02*
X02284Y04232D01*
X02279Y04228*
X02275Y04223*
X02274Y04217*
X02275Y0421*
X02279Y04205*
X02284Y04201*
X0229Y042*
X02297Y04201*
X02302Y04205*
X02305Y0421*
X02307Y04217*
X02305Y04223*
X02302Y04228*
X02297Y04232*
X0229Y04233*
G37*
G36*
X04387Y04222D02*
X04381Y04221D01*
X04376Y04217*
X04372Y04212*
X04371Y04206*
X04372Y04199*
X04376Y04194*
X04381Y0419*
X04387Y04189*
X04394Y0419*
X04399Y04194*
X04402Y04199*
X04404Y04206*
X04402Y04212*
X04399Y04217*
X04394Y04221*
X04387Y04222*
G37*
G36*
X0491Y04219D02*
X04904Y04218D01*
X04899Y04214*
X04895Y04209*
X04894Y04203*
X04895Y04196*
X04899Y04191*
X04904Y04187*
X0491Y04186*
X04917Y04187*
X04922Y04191*
X04925Y04196*
X04927Y04203*
X04925Y04209*
X04922Y04214*
X04917Y04218*
X0491Y04219*
G37*
G36*
X03958Y04152D02*
X03951Y04151D01*
X03945Y04148*
X03939Y04144*
X03935Y04139*
X03933Y04132*
X03932Y04126*
X03933Y04119*
X03935Y04113*
X03939Y04107*
X03945Y04103*
X03951Y04101*
X03958Y041*
X03964Y04101*
X03971Y04103*
X03976Y04107*
X0398Y04113*
X03983Y04119*
X03984Y04126*
X03983Y04132*
X0398Y04139*
X03976Y04144*
X03971Y04148*
X03964Y04151*
X03958Y04152*
G37*
G36*
X03784D02*
X03778Y04151D01*
X03771Y04148*
X03766Y04144*
X03762Y04139*
X03759Y04132*
X03758Y04126*
X03759Y04119*
X03762Y04113*
X03766Y04107*
X03771Y04103*
X03778Y04101*
X03784Y041*
X03791Y04101*
X03797Y04103*
X03803Y04107*
X03807Y04113*
X03809Y04119*
X0381Y04126*
X03809Y04132*
X03807Y04139*
X03803Y04144*
X03797Y04148*
X03791Y04151*
X03784Y04152*
G37*
G36*
X04754Y04132D02*
X04748Y04131D01*
X04743Y04127*
X04739Y04122*
X04738Y04115*
X04739Y04109*
X04743Y04104*
X04748Y041*
X04754Y04099*
X0476Y041*
X04766Y04104*
X04769Y04109*
X04771Y04115*
X04769Y04122*
X04766Y04127*
X0476Y04131*
X04754Y04132*
G37*
G36*
X02146Y0412D02*
X02139Y04118D01*
X02134Y04115*
X02131Y0411*
X02129Y04103*
X02131Y04097*
X02134Y04092*
X02139Y04088*
X02146Y04087*
X02152Y04088*
X02157Y04092*
X02161Y04097*
X02162Y04103*
X02161Y0411*
X02157Y04115*
X02152Y04118*
X02146Y0412*
G37*
G36*
X05267Y04105D02*
X0526Y04103D01*
X05255Y041*
X05251Y04095*
X0525Y04088*
X05251Y04082*
X05255Y04077*
X0526Y04073*
X05267Y04072*
X05273Y04073*
X05278Y04077*
X05282Y04082*
X05283Y04088*
X05282Y04095*
X05278Y041*
X05273Y04103*
X05267Y04105*
G37*
G36*
X02253Y04102D02*
X02247Y04101D01*
X02242Y04098*
X02238Y04092*
X02237Y04086*
X02238Y0408*
X02242Y04075*
X02247Y04071*
X02253Y0407*
X0226Y04071*
X02265Y04075*
X02269Y0408*
X0227Y04086*
X02269Y04092*
X02265Y04098*
X0226Y04101*
X02253Y04102*
G37*
G36*
X03504Y04102D02*
X03498Y04101D01*
X03493Y04097*
X03489Y04092*
X03488Y04086*
X03489Y04079*
X03493Y04074*
X03498Y0407*
X03504Y04069*
X03511Y0407*
X03516Y04074*
X03519Y04079*
X03521Y04086*
X03519Y04092*
X03516Y04097*
X03511Y04101*
X03504Y04102*
G37*
G36*
X03294Y04127D02*
X03284Y04126D01*
X03274Y04121*
X03265Y04115*
X03259Y04106*
X03254Y04096*
X03253Y04086*
X03254Y04075*
X03259Y04065*
X03265Y04056*
X03274Y0405*
X03284Y04046*
X03294Y04044*
X03305Y04046*
X03315Y0405*
X03324Y04056*
X0333Y04065*
X03334Y04075*
X03336Y04086*
X03334Y04096*
X0333Y04106*
X03324Y04115*
X03315Y04121*
X03305Y04126*
X03294Y04127*
G37*
G36*
X02994D02*
X02984Y04126D01*
X02974Y04121*
X02965Y04115*
X02959Y04106*
X02954Y04096*
X02953Y04086*
X02954Y04075*
X02959Y04065*
X02965Y04056*
X02974Y0405*
X02984Y04046*
X02994Y04044*
X03005Y04046*
X03015Y0405*
X03024Y04056*
X0303Y04065*
X03034Y04075*
X03036Y04086*
X03034Y04096*
X0303Y04106*
X03024Y04115*
X03015Y04121*
X03005Y04126*
X02994Y04127*
G37*
G36*
X03777Y04039D02*
X03771Y04038D01*
X03766Y04034*
X03762Y04029*
X03761Y04023*
X03762Y04016*
X03766Y04011*
X03771Y04007*
X03777Y04006*
X03784Y04007*
X03789Y04011*
X03792Y04016*
X03794Y04023*
X03792Y04029*
X03789Y04034*
X03784Y04038*
X03777Y04039*
G37*
G36*
X06164Y04108D02*
X06075D01*
X06061Y04107*
X06049Y04101*
X06038Y04093*
X06029Y04082*
X06024Y04069*
X06022Y04056*
X06024Y04042*
X06029Y04029*
X06038Y04018*
X06049Y0401*
X06061Y04005*
X06075Y04003*
X06164*
X06177Y04005*
X0619Y0401*
X06201Y04018*
X06209Y04029*
X06215Y04042*
X06216Y04056*
X06215Y04069*
X06209Y04082*
X06201Y04093*
X0619Y04101*
X06177Y04107*
X06164Y04108*
G37*
G36*
X02353Y04034D02*
X02347Y04032D01*
X02341Y04029*
X02338Y04023*
X02337Y04017*
X02338Y04011*
X02341Y04006*
X02347Y04002*
X02353Y04001*
X02359Y04002*
X02364Y04006*
X02368Y04011*
X02369Y04017*
X02368Y04023*
X02364Y04029*
X02359Y04032*
X02353Y04034*
G37*
G36*
X05723Y04083D02*
X05708Y04081D01*
X05694Y04075*
X05682Y04066*
X05673Y04054*
X05667Y0404*
X05665Y04025*
X05667Y0401*
X05673Y03996*
X05682Y03984*
X05694Y03975*
X05708Y03969*
X05723Y03967*
X05738Y03969*
X05752Y03975*
X05764Y03984*
X05773Y03996*
X05779Y0401*
X05781Y04025*
X05779Y0404*
X05773Y04054*
X05764Y04066*
X05752Y04075*
X05738Y04081*
X05723Y04083*
G37*
G36*
X02084Y03912D02*
X02078Y03911D01*
X02073Y03907*
X02069Y03902*
X02068Y03896*
X02069Y03889*
X02069Y03889*
X02066Y03885*
X02066Y03886*
X02059Y03887*
X02053Y03886*
X02048Y03882*
X02044Y03877*
X02043Y03871*
X02044Y03864*
X02048Y03859*
X02053Y03855*
X02059Y03854*
X02066Y03855*
X02071Y03859*
X02074Y03864*
X02076Y03871*
X02074Y03877*
X02074Y03877*
X02078Y03881*
X02078Y0388*
X02084Y03879*
X02091Y0388*
X02096Y03884*
X02099Y03889*
X02101Y03896*
X02099Y03902*
X02096Y03907*
X02091Y03911*
X02084Y03912*
G37*
G36*
X05934Y04034D02*
X05921Y04033D01*
X05908Y04027*
X05897Y04019*
X05889Y04008*
X05883Y03995*
X05882Y03982*
Y03893*
X05883Y0388*
X05889Y03867*
X05897Y03856*
X05908Y03847*
X05921Y03842*
X05934Y0384*
X05948Y03842*
X05961Y03847*
X05972Y03856*
X0598Y03867*
X05985Y0388*
X05987Y03893*
Y03982*
X05985Y03995*
X0598Y04008*
X05972Y04019*
X05961Y04027*
X05948Y04033*
X05934Y04034*
G37*
G36*
X03699Y03852D02*
X03693Y03851D01*
X03688Y03847*
X03684Y03842*
X03683Y03836*
X03684Y03829*
X03688Y03824*
X03693Y0382*
X03699Y03819*
X03706Y0382*
X03711Y03824*
X03714Y03829*
X03716Y03836*
X03714Y03842*
X03711Y03847*
X03706Y03851*
X03699Y03852*
G37*
G36*
X03014Y03847D02*
X03008Y03846D01*
X03003Y03842*
X02999Y03837*
X02998Y03831*
X02999Y03824*
X03003Y03819*
X03008Y03815*
X03014Y03814*
X03021Y03815*
X03026Y03819*
X03029Y03824*
X03031Y03831*
X03029Y03837*
X03026Y03842*
X03021Y03846*
X03014Y03847*
G37*
G36*
X05723Y03902D02*
X05708Y039D01*
X05694Y03894*
X05682Y03885*
X05673Y03873*
X05667Y03859*
X05665Y03844*
X05667Y03829*
X05673Y03815*
X05682Y03803*
X05694Y03794*
X05708Y03788*
X05723Y03786*
X05738Y03788*
X05752Y03794*
X05764Y03803*
X05773Y03815*
X05779Y03829*
X05781Y03844*
X05779Y03859*
X05773Y03873*
X05764Y03885*
X05752Y03894*
X05738Y039*
X05723Y03902*
G37*
G36*
X03269Y03804D02*
X03263Y03803D01*
X03258Y03799*
X03254Y03794*
X03253Y03788*
X03254Y03781*
X03258Y03776*
X03263Y03772*
X03269Y03771*
X03276Y03772*
X03281Y03776*
X03284Y03781*
X03286Y03788*
X03284Y03794*
X03281Y03799*
X03276Y03803*
X03269Y03804*
G37*
G36*
X0286Y03803D02*
X02854Y03802D01*
X02849Y03798*
X02845Y03793*
X02844Y03787*
X02845Y0378*
X02849Y03775*
X02854Y03771*
X0286Y0377*
X02867Y03771*
X02872Y03775*
X02875Y0378*
X02877Y03787*
X02875Y03793*
X02872Y03798*
X02867Y03802*
X0286Y03803*
G37*
G36*
X06169Y03877D02*
X0607D01*
X06055Y03875*
X06041Y03869*
X06029Y0386*
X0602Y03848*
X06014Y03834*
X06012Y03819*
X06014Y03804*
X0602Y0379*
X06029Y03779*
X06041Y03769*
X06055Y03764*
X0607Y03762*
X06169*
X06183Y03764*
X06197Y03769*
X06209Y03779*
X06219Y0379*
X06224Y03804*
X06226Y03819*
X06224Y03834*
X06219Y03848*
X06209Y0386*
X06197Y03869*
X06183Y03875*
X06169Y03877*
G37*
G36*
X0383Y03778D02*
X03824Y03777D01*
X03819Y03773*
X03815Y03768*
X03814Y03762*
X03815Y03755*
X03819Y0375*
X03824Y03746*
X0383Y03745*
X03837Y03746*
X03842Y0375*
X03845Y03755*
X03847Y03762*
X03845Y03768*
X03842Y03773*
X03837Y03777*
X0383Y03778*
G37*
G36*
X02531Y03962D02*
X02514Y0396D01*
X02497Y03956*
X02482Y0395*
X02467Y03941*
X02454Y0393*
X02443Y03917*
X02434Y03902*
X02428Y03887*
X02424Y0387*
X02423Y03853*
X02424Y03836*
X02428Y0382*
X02434Y03804*
X02443Y03789*
X02454Y03777*
X02467Y03766*
X02482Y03757*
X02497Y0375*
X02514Y03746*
X02531Y03745*
X02548Y03746*
X02564Y0375*
X0258Y03757*
X02595Y03766*
X02608Y03777*
X02619Y03789*
X02627Y03804*
X02634Y0382*
X02638Y03836*
X02639Y03853*
X02638Y0387*
X02634Y03887*
X02627Y03902*
X02619Y03917*
X02608Y0393*
X02595Y03941*
X0258Y0395*
X02564Y03956*
X02548Y0396*
X02531Y03962*
G37*
G36*
X03699Y03767D02*
X03693Y03766D01*
X03688Y03762*
X03684Y03757*
X03683Y03751*
X03684Y03744*
X03688Y03739*
X03693Y03735*
X03699Y03734*
X03706Y03735*
X03711Y03739*
X03714Y03744*
X03716Y03751*
X03714Y03757*
X03711Y03762*
X03706Y03766*
X03699Y03767*
G37*
G36*
X02993D02*
X02987Y03766D01*
X02981Y03762*
X02978Y03757*
X02977Y03751*
X02978Y03744*
X02981Y03739*
X02987Y03735*
X02993Y03734*
X02999Y03735*
X03004Y03739*
X03008Y03744*
X03009Y03751*
X03008Y03757*
X03004Y03762*
X02999Y03766*
X02993Y03767*
G37*
G36*
X02258Y03757D02*
X02252Y03756D01*
X02247Y03752*
X02243Y03747*
X02242Y03741*
X02243Y03734*
X02247Y03729*
X02252Y03725*
X02258Y03724*
X02265Y03725*
X0227Y03729*
X02273Y03734*
X02275Y03741*
X02273Y03747*
X0227Y03752*
X02265Y03756*
X02258Y03757*
G37*
G36*
X02139Y03754D02*
X02133Y03753D01*
X02128Y03749*
X02124Y03744*
X02123Y03738*
X02124Y03731*
X02128Y03726*
X02133Y03722*
X02139Y03721*
X02146Y03722*
X02151Y03726*
X02154Y03731*
X02156Y03738*
X02154Y03744*
X02151Y03749*
X02146Y03753*
X02139Y03754*
G37*
G36*
X02724Y03745D02*
X02718Y03744D01*
X02713Y0374*
X02709Y03735*
X02708Y03729*
X02709Y03722*
X02713Y03717*
X02718Y03713*
X02724Y03712*
X02731Y03713*
X02736Y03717*
X02739Y03722*
X02741Y03729*
X02739Y03735*
X02736Y0374*
X02731Y03744*
X02724Y03745*
G37*
G36*
X02422Y03624D02*
X02413Y03623D01*
X02405Y03617*
X024Y0361*
X02398Y03601*
X024Y03592*
X02405Y03584*
X02413Y03579*
X02422Y03577*
X02431Y03579*
X02438Y03584*
X02443Y03592*
X02445Y03601*
X02443Y0361*
X02438Y03617*
X02431Y03623*
X02422Y03624*
G37*
G36*
X05733Y03572D02*
X05727Y03571D01*
X05722Y03567*
X05718Y03562*
X05717Y03556*
X05718Y03549*
X05722Y03544*
X05727Y0354*
X05733Y03539*
X0574Y0354*
X05745Y03544*
X05748Y03549*
X0575Y03556*
X05748Y03562*
X05745Y03567*
X0574Y03571*
X05733Y03572*
G37*
G36*
X05676Y03562D02*
X0567Y03561D01*
X05665Y03557*
X05661Y03552*
X0566Y03546*
X05661Y03539*
X05665Y03534*
X0567Y0353*
X05676Y03529*
X05683Y0353*
X05688Y03534*
X05691Y03539*
X05693Y03546*
X05691Y03552*
X05688Y03557*
X05683Y03561*
X05676Y03562*
G37*
G36*
X02434D02*
X02428Y03561D01*
X02423Y03557*
X02419Y03552*
X02418Y03546*
X02419Y03539*
X02423Y03534*
X02428Y0353*
X02434Y03529*
X02441Y0353*
X02446Y03534*
X02449Y03539*
X02451Y03546*
X02449Y03552*
X02446Y03557*
X02441Y03561*
X02434Y03562*
G37*
G36*
X02254Y03552D02*
X02248Y03551D01*
X02243Y03547*
X02239Y03542*
X02238Y03536*
X02239Y03529*
X02242Y03525*
X02239Y03521*
X02234Y03522*
X02228Y03521*
X02223Y03517*
X02219Y03512*
X02218Y03506*
X02219Y03499*
X02223Y03494*
X02228Y0349*
X02234Y03489*
X02241Y0349*
X02246Y03494*
X02249Y03499*
X02251Y03506*
X02249Y03512*
X02247Y03516*
X0225Y0352*
X02254Y03519*
X02261Y0352*
X02266Y03524*
X02269Y03529*
X02271Y03536*
X02269Y03542*
X02266Y03547*
X02261Y03551*
X02254Y03552*
G37*
G36*
X02389Y03497D02*
X02383Y03496D01*
X02378Y03492*
X02374Y03487*
X02373Y03481*
X02374Y03474*
X02378Y03469*
X02383Y03465*
X02389Y03464*
X02396Y03465*
X02401Y03469*
X02404Y03474*
X02406Y03481*
X02404Y03487*
X02401Y03492*
X02396Y03496*
X02389Y03497*
G37*
G36*
X02422Y03467D02*
X02413Y03465D01*
X02405Y0346*
X024Y03452*
X02398Y03443*
X024Y03434*
X02405Y03427*
X02413Y03422*
X02422Y0342*
X02431Y03422*
X02438Y03427*
X02443Y03434*
X02445Y03443*
X02443Y03452*
X02438Y0346*
X02431Y03465*
X02422Y03467*
G37*
G36*
X02321Y03377D02*
X02315Y03376D01*
X0231Y03372*
X02306Y03367*
X02305Y03361*
X02306Y03354*
X0231Y03349*
X02315Y03345*
X02321Y03344*
X02327Y03345*
X02333Y03349*
X02336Y03354*
X02337Y03361*
X02336Y03367*
X02333Y03372*
X02327Y03376*
X02321Y03377*
G37*
G36*
X02259Y03277D02*
X02253Y03276D01*
X02248Y03272*
X02244Y03267*
X02243Y03261*
X02244Y03254*
X02248Y03249*
X02253Y03245*
X02259Y03244*
X02266Y03245*
X02271Y03249*
X02274Y03254*
X02276Y03261*
X02274Y03267*
X02271Y03272*
X02266Y03276*
X02259Y03277*
G37*
G36*
X02205Y03216D02*
X02199Y03215D01*
X02194Y03211*
X0219Y03206*
X02189Y032*
X0219Y03193*
X02194Y03188*
X02199Y03184*
X02205Y03183*
X02212Y03184*
X02217Y03188*
X0222Y03193*
X02222Y032*
X0222Y03206*
X02217Y03211*
X02212Y03215*
X02205Y03216*
G37*
G36*
X04477Y03151D02*
X04471Y0315D01*
X04466Y03146*
X04462Y03141*
X04461Y03135*
X04462Y03128*
X04466Y03123*
X04471Y03119*
X04477Y03118*
X04484Y03119*
X04489Y03123*
X04492Y03128*
X04494Y03135*
X04492Y03141*
X04489Y03146*
X04484Y0315*
X04477Y03151*
G37*
G36*
X04431D02*
X04425Y0315D01*
X0442Y03146*
X04416Y03141*
X04415Y03135*
X04416Y03128*
X0442Y03123*
X04425Y03119*
X04431Y03118*
X04438Y03119*
X04443Y03123*
X04446Y03128*
X04448Y03135*
X04446Y03141*
X04443Y03146*
X04438Y0315*
X04431Y03151*
G37*
G36*
X06253Y02925D02*
X06247Y02924D01*
X06242Y0292*
X06238Y02915*
X06237Y02909*
X06238Y02903*
X06242Y02897*
X06247Y02894*
X06253Y02893*
X0626Y02894*
X06265Y02897*
X06269Y02903*
X0627Y02909*
X06269Y02915*
X06265Y0292*
X0626Y02924*
X06253Y02925*
G37*
G36*
X04794Y02824D02*
X04788Y02823D01*
X04782Y02819*
X04779Y02814*
X04777Y02808*
X04779Y02801*
X04782Y02796*
X04788Y02793*
X04794Y02791*
X048Y02793*
X04805Y02796*
X04809Y02801*
X0481Y02808*
X04809Y02814*
X04805Y02819*
X048Y02823*
X04794Y02824*
G37*
G36*
X05578Y02534D02*
X05566Y02533D01*
X05555Y02528*
X05545Y02521*
X05538Y02511*
X05533Y025*
X05532Y02489*
X05533Y02477*
X05538Y02466*
X05545Y02456*
X05555Y02449*
X05566Y02444*
X05578Y02443*
X0559Y02444*
X05601Y02449*
X0561Y02456*
X05617Y02466*
X05622Y02477*
X05624Y02489*
X05622Y025*
X05617Y02511*
X0561Y02521*
X05601Y02528*
X0559Y02533*
X05578Y02534*
G37*
G36*
X06004Y0245D02*
X05998Y02449D01*
X05993Y02445*
X05989Y0244*
X05988Y02434*
X05989Y02427*
X05993Y02422*
X05998Y02418*
X06004Y02417*
X06011Y02418*
X06016Y02422*
X06019Y02427*
X06021Y02434*
X06019Y0244*
X06016Y02445*
X06011Y02449*
X06004Y0245*
G37*
G36*
X069Y03647D02*
X06885Y03645D01*
X06871Y03639*
X06859Y0363*
X0685Y03618*
X06844Y03604*
X06842Y03589*
X06844Y03574*
X0685Y0356*
X06859Y03548*
X06871Y03539*
X06885Y03533*
X069Y03531*
X06915Y03533*
X06929Y03539*
X06941Y03548*
X0695Y0356*
X06955Y03574*
X06957Y03589*
X06955Y03604*
X0695Y03618*
X06941Y0363*
X06929Y03639*
X06915Y03645*
X069Y03647*
G37*
G36*
X06734D02*
X06719Y03645D01*
X06705Y03639*
X06694Y0363*
X06684Y03618*
X06679Y03604*
X06677Y03589*
X06679Y03574*
X06684Y0356*
X06694Y03548*
X06705Y03539*
X06719Y03533*
X06734Y03531*
X06749Y03533*
X06763Y03539*
X06775Y03548*
X06784Y0356*
X0679Y03574*
X06792Y03589*
X0679Y03604*
X06784Y03618*
X06775Y0363*
X06763Y03639*
X06749Y03645*
X06734Y03647*
G37*
G36*
X06569D02*
X06554Y03645D01*
X0654Y03639*
X06528Y0363*
X06519Y03618*
X06513Y03604*
X06511Y03589*
X06513Y03574*
X06519Y0356*
X06528Y03548*
X0654Y03539*
X06554Y03533*
X06569Y03531*
X06584Y03533*
X06598Y03539*
X0661Y03548*
X06619Y0356*
X06625Y03574*
X06627Y03589*
X06625Y03604*
X06619Y03618*
X0661Y0363*
X06598Y03639*
X06584Y03645*
X06569Y03647*
G37*
G36*
X06509Y03472D02*
X06503Y03471D01*
X06498Y03467*
X06494Y03462*
X06493Y03456*
X06494Y03449*
X06498Y03444*
X06503Y0344*
X06509Y03439*
X06516Y0344*
X06521Y03444*
X06524Y03449*
X06526Y03456*
X06524Y03462*
X06521Y03467*
X06516Y03471*
X06509Y03472*
G37*
G36*
X06479Y03442D02*
X06473Y03441D01*
X06468Y03437*
X06464Y03432*
X06463Y03426*
X06464Y03419*
X06468Y03414*
X06473Y0341*
X06479Y03409*
X06486Y0341*
X06491Y03414*
X06494Y03419*
X06496Y03426*
X06494Y03432*
X06491Y03437*
X06486Y03441*
X06479Y03442*
G37*
G36*
X06447Y03412D02*
X06441Y03411D01*
X06436Y03407*
X06432Y03402*
X06431Y03396*
X06432Y03389*
X06436Y03384*
X06441Y0338*
X06447Y03379*
X06453Y0338*
X06459Y03384*
X06462Y03389*
X06463Y03396*
X06462Y03402*
X06459Y03407*
X06453Y03411*
X06447Y03412*
G37*
G36*
X06409Y03387D02*
X06403Y03386D01*
X06398Y03382*
X06394Y03377*
X06393Y03371*
X06394Y03364*
X06398Y03359*
X06403Y03355*
X06409Y03354*
X06416Y03355*
X06421Y03359*
X06424Y03364*
X06426Y03371*
X06424Y03377*
X06421Y03382*
X06416Y03386*
X06409Y03387*
G37*
G36*
X06648Y03357D02*
X06642Y03356D01*
X06637Y03352*
X06633Y03347*
X06632Y03341*
X06633Y03334*
X06637Y03329*
X06642Y03325*
X06648Y03324*
X06655Y03325*
X0666Y03329*
X06663Y03334*
X06665Y03341*
X06663Y03347*
X0666Y03352*
X06655Y03356*
X06648Y03357*
G37*
G36*
X06354Y03347D02*
X06348Y03346D01*
X06343Y03342*
X06339Y03337*
X06338Y03331*
X06339Y03324*
X06343Y03319*
X06348Y03316*
X06354Y03314*
X0636Y03316*
X06366Y03319*
X06369Y03324*
X06371Y03331*
X06369Y03337*
X06366Y03342*
X0636Y03346*
X06354Y03347*
G37*
G36*
X06444Y03307D02*
X06438Y03306D01*
X06433Y03302*
X06429Y03297*
X06428Y03291*
X06429Y03284*
X06433Y03279*
X06438Y03275*
X06444Y03274*
X06451Y03275*
X06456Y03279*
X06459Y03284*
X06461Y03291*
X06459Y03297*
X06456Y03302*
X06451Y03306*
X06444Y03307*
G37*
G36*
X06334Y03282D02*
X06328Y03281D01*
X06323Y03277*
X06319Y03272*
X06318Y03266*
X06319Y03259*
X06323Y03254*
X06328Y0325*
X06334Y03249*
X06341Y0325*
X06346Y03254*
X06349Y03259*
X06351Y03266*
X06349Y03272*
X06346Y03277*
X06341Y03281*
X06334Y03282*
G37*
G36*
X06476Y03247D02*
X0647Y03246D01*
X06465Y03242*
X06461Y03237*
X0646Y03231*
X06461Y03224*
X06465Y03219*
X0647Y03215*
X06476Y03214*
X06483Y03215*
X06488Y03219*
X06491Y03224*
X06493Y03231*
X06491Y03237*
X06488Y03242*
X06483Y03246*
X06476Y03247*
G37*
G36*
X06282Y03242D02*
X06276Y03241D01*
X0627Y03237*
X06267Y03232*
X06266Y03226*
X06267Y03219*
X0627Y03214*
X06276Y0321*
X06282Y03209*
X06288Y0321*
X06293Y03214*
X06297Y03219*
X06298Y03226*
X06297Y03232*
X06293Y03237*
X06288Y03241*
X06282Y03242*
G37*
G36*
X06309Y03215D02*
X06303Y03214D01*
X06297Y0321*
X06294Y03205*
X06293Y03199*
X06294Y03192*
X06297Y03187*
X06303Y03183*
X06309Y03182*
X06315Y03183*
X0632Y03187*
X06324Y03192*
X06325Y03199*
X06324Y03205*
X0632Y0321*
X06315Y03214*
X06309Y03215*
G37*
G36*
X06439Y03207D02*
X06433Y03206D01*
X06428Y03202*
X06424Y03197*
X06423Y03191*
X06424Y03184*
X06428Y03179*
X06433Y03175*
X06439Y03174*
X06446Y03175*
X06451Y03179*
X06454Y03184*
X06456Y03191*
X06454Y03197*
X06451Y03202*
X06446Y03206*
X06439Y03207*
G37*
G36*
X06339Y03167D02*
X06333Y03166D01*
X06328Y03162*
X06324Y03157*
X06323Y03151*
X06324Y03144*
X06328Y03139*
X06333Y03135*
X06339Y03134*
X06346Y03135*
X06351Y03139*
X06354Y03144*
X06356Y03151*
X06354Y03157*
X06351Y03162*
X06346Y03166*
X06339Y03167*
G37*
G36*
X06647Y03146D02*
X06641Y03144D01*
X06636Y03141*
X06632Y03136*
X06631Y03129*
X06632Y03123*
X06636Y03118*
X06641Y03114*
X06647Y03113*
X06653Y03114*
X06659Y03118*
X06662Y03123*
X06663Y03129*
X06662Y03136*
X06659Y03141*
X06653Y03144*
X06647Y03146*
G37*
G36*
X06304Y03137D02*
X06298Y03136D01*
X06293Y03132*
X06289Y03127*
X06288Y03121*
X06289Y03114*
X06293Y03109*
X06298Y03105*
X06304Y03104*
X06311Y03105*
X06316Y03109*
X06319Y03114*
X06321Y03121*
X06319Y03127*
X06316Y03132*
X06311Y03136*
X06304Y03137*
G37*
G36*
X06626Y03048D02*
X0662Y03047D01*
X06615Y03043*
X06611Y03038*
X0661Y03032*
X06611Y03025*
X06615Y0302*
X0662Y03016*
X06626Y03015*
X06633Y03016*
X06638Y0302*
X06641Y03025*
X06643Y03032*
X06641Y03038*
X06638Y03043*
X06633Y03047*
X06626Y03048*
G37*
G36*
X06456Y03025D02*
X0645Y03024D01*
X06445Y0302*
X06441Y03015*
X0644Y03009*
X06441Y03002*
X06445Y02997*
X0645Y02993*
X06456Y02992*
X06463Y02993*
X06468Y02997*
X06471Y03002*
X06473Y03009*
X06471Y03015*
X06468Y0302*
X06463Y03024*
X06456Y03025*
G37*
G36*
X06372Y02925D02*
X06365Y02924D01*
X0636Y0292*
X06356Y02915*
X06355Y02909*
X06356Y02903*
X0636Y02897*
X06365Y02894*
X06372Y02893*
X06378Y02894*
X06383Y02897*
X06387Y02903*
X06388Y02909*
X06387Y02915*
X06383Y0292*
X06378Y02924*
X06372Y02925*
G37*
G36*
X06398Y02673D02*
X06392Y02672D01*
X06387Y02668*
X06383Y02663*
X06382Y02657*
X06383Y0265*
X06387Y02645*
X06392Y02641*
X06398Y0264*
X06405Y02641*
X0641Y02645*
X06413Y0265*
X06415Y02657*
X06413Y02663*
X0641Y02668*
X06405Y02672*
X06398Y02673*
G37*
G36*
X06397Y02626D02*
X06391Y02625D01*
X06386Y02621*
X06382Y02616*
X06381Y0261*
X06382Y02603*
X06386Y02598*
X06391Y02594*
X06397Y02593*
X06404Y02594*
X06409Y02598*
X06412Y02603*
X06414Y0261*
X06412Y02616*
X06409Y02621*
X06404Y02625*
X06397Y02626*
G37*
G36*
X06396Y02572D02*
X0639Y02571D01*
X06385Y02567*
X06381Y02562*
X0638Y02556*
X06381Y02549*
X06385Y02544*
X0639Y0254*
X06396Y02539*
X06403Y0254*
X06408Y02544*
X06411Y02549*
X06413Y02556*
X06411Y02562*
X06408Y02567*
X06403Y02571*
X06396Y02572*
G37*
G36*
X06397Y02517D02*
X06391Y02516D01*
X06386Y02512*
X06382Y02507*
X06381Y02501*
X06382Y02494*
X06386Y02489*
X06391Y02485*
X06397Y02484*
X06404Y02485*
X06409Y02489*
X06412Y02494*
X06414Y02501*
X06412Y02507*
X06409Y02512*
X06404Y02516*
X06397Y02517*
G37*
G36*
X06398Y02469D02*
X06392Y02468D01*
X06387Y02464*
X06383Y02459*
X06382Y02453*
X06383Y02446*
X06387Y02441*
X06392Y02437*
X06398Y02436*
X06405Y02437*
X0641Y02441*
X06413Y02446*
X06415Y02453*
X06413Y02459*
X0641Y02464*
X06405Y02468*
X06398Y02469*
G37*
G36*
X06607Y02192D02*
X06601Y02191D01*
X06596Y02187*
X06592Y02182*
X06591Y02176*
X06592Y02169*
X06596Y02164*
X06601Y0216*
X06607Y02159*
X06614Y0216*
X06619Y02164*
X06622Y02169*
X06624Y02176*
X06622Y02182*
X06619Y02187*
X06614Y02191*
X06607Y02192*
G37*
G36*
X06949Y02111D02*
X06943Y0211D01*
X06938Y02106*
X06934Y02101*
X06933Y02095*
X06934Y02088*
X06938Y02083*
X06943Y02079*
X06949Y02078*
X06956Y02079*
X06961Y02083*
X06964Y02088*
X06966Y02095*
X06964Y02101*
X06961Y02106*
X06956Y0211*
X06949Y02111*
G37*
G36*
X06974Y01956D02*
X06968Y01955D01*
X06962Y01951*
X06959Y01946*
X06958Y01939*
X06959Y01933*
X06962Y01928*
X06968Y01924*
X06974Y01923*
X0698Y01924*
X06985Y01928*
X06989Y01933*
X0699Y01939*
X06989Y01946*
X06985Y01951*
X0698Y01955*
X06974Y01956*
G37*
%LNgrandmaster-3*%
%LPD*%
G54D13*
X02415Y02792D02*
Y02823D01*
Y02792D02*
X02419Y02788D01*
X02394Y02845D02*
X02415Y02823D01*
X02397Y03279D02*
X02413Y03295D01*
X02631Y02876D02*
X02632Y02877D01*
Y02971*
X02434Y0298D02*
X02473D01*
X02421Y02967D02*
X02434Y0298D01*
X02398Y02949D02*
X02415Y02967D01*
X02421*
X02398Y02944D02*
Y02949D01*
X02334Y03279D02*
X02397D01*
X02385Y02854D02*
X02386D01*
X02394Y02846*
Y02845D02*
Y02846D01*
G54D19*
X01798Y0013D02*
Y00355D01*
X01896Y00735D02*
X02191Y0044D01*
X02349Y00111D02*
X02349Y00111D01*
X02191Y00111D02*
Y0044D01*
X01896Y01516D02*
X01897Y01516D01*
X01896Y00735D02*
Y01516D01*
X03018Y00111D02*
X03019Y00112D01*
X02703Y00111D02*
X02704Y00112D01*
X02711Y03002D02*
Y03003D01*
X02681Y02971D02*
X02711Y03002D01*
X02632Y02971D02*
X02681D01*
X0259Y03187D02*
X02591Y03186D01*
X02529Y03121D02*
X02591Y03184D01*
Y03186*
X02589Y03287D02*
X0259Y03288D01*
X02583Y03279D02*
X02589Y03285D01*
X02509Y03279D02*
X02583D01*
X02589Y03285D02*
Y03287D01*
X02415Y03121D02*
X02418Y03118D01*
X02334Y03121D02*
X02415D01*
X02334Y032D02*
X02335Y03199D01*
X02414*
X02462Y03172D02*
X0249Y032D01*
X02509*
Y03121D02*
X02529D01*
X04049Y03665D02*
Y03701D01*
X03944Y03806D02*
X04049Y03701D01*
X03829Y03806D02*
X03944D01*
G54D21*
X0298Y00408D02*
D01*
X0298Y00408*
X0298Y00408*
X0298Y00407*
X02821Y00407D02*
D01*
X02821Y00407*
X02821Y00407*
X02821Y00407*
X0282Y00407*
X0282Y00406*
X0282Y00406*
X0282Y00406*
X02819Y00406*
X02819Y00405*
X02819Y00405*
X02819Y00405*
X02819Y00404*
X02819Y00404*
X02818Y00404*
X02818Y00403*
X02818Y00403*
Y00403*
X02469Y0041D02*
D01*
X02469Y0041*
X02469Y0041*
X02469Y0041*
X02469Y00409*
X02468Y00409*
X02468Y00409*
X02468Y00408*
X02468Y00408*
X02468Y00408*
X02468Y00407*
X02468Y00407*
X02854Y00364D02*
D01*
X02854Y00364*
X02854Y00363*
X02854Y00363*
X02854Y00363*
X02854Y00363*
X02854Y00363*
X02854Y00363*
X02854Y00363*
X02854Y00363*
X02854Y00363*
X02854Y00363*
X02854Y00362*
X02818Y00365D02*
D01*
X02818Y00365*
X02818Y00364*
X02818Y00364*
X02819Y00364*
X02819Y00364*
X02819Y00363*
X02819Y00363*
X02819Y00363*
X02819Y00363*
X02819Y00363*
X02819Y00363*
X02819Y00362*
X02664D02*
D01*
X02664Y00363*
X02665Y00363*
X02665Y00363*
X02665Y00363*
X02665Y00363*
X02665Y00363*
X02665Y00363*
X02665Y00363*
X02665Y00363*
X02665Y00364*
X02665Y00364*
X02665Y00364*
X02349Y00362D02*
D01*
X02349Y00363*
X0235Y00363*
X0235Y00363*
X0235Y00363*
X0235Y00363*
X0235Y00363*
X0235Y00363*
X0235Y00363*
X0235Y00364*
X0235Y00364*
X0235Y00364*
Y00364*
X02979Y00362D02*
D01*
X02979Y00363*
X02979Y00363*
X0298Y00363*
X0298Y00363*
X0298Y00363*
X0298Y00363*
X0298Y00363*
X0298Y00363*
X0298Y00363*
X0298Y00363*
X0298Y00364*
X0298Y00364*
X02349Y00329D02*
D01*
X02349Y00329*
X02349Y00328*
X02349Y00328*
X02349Y00328*
X02349Y00328*
X02349Y00328*
X02349Y00328*
X02349Y00328*
X02349Y00327*
X02349Y00327*
X02349Y00327*
Y00327*
X02348Y00137D02*
D01*
X02348Y00138*
X02348Y00138*
X02349Y00138*
X02349Y00138*
X02349Y00139*
X02349Y00139*
X02349Y00139*
X02349Y0014*
X02349Y0014*
X02349Y0014*
X02349Y00141*
X02349Y00141*
X02387Y00137D02*
D01*
X02388Y00138*
X02388Y00138*
X02388Y00138*
X02388Y00139*
X02389Y00139*
X02389Y0014*
X02389Y0014*
X02389Y00141*
X02389Y00141*
X02389Y00142*
X02389Y00142*
X02389Y00142*
X02466Y00137D02*
D01*
X02466Y00138*
X02467Y00138*
X02467Y00139*
X02467Y00139*
X02468Y0014*
X02468Y0014*
X02468Y00141*
X02468Y00141*
X02468Y00142*
X02468Y00142*
X02468Y00143*
X02468Y00143*
X02505Y00137D02*
D01*
X02506Y00138*
X02507Y00139*
X02508Y00141*
X02509Y00142*
X02509Y00143*
X0251Y00144*
X0251Y00146*
X02511Y00147*
X02511Y00148*
X02511Y0015*
X02511Y00151*
X02511Y00152*
X02663Y00137D02*
D01*
X02663Y00138*
X02663Y00138*
X02664Y00138*
X02664Y00138*
X02664Y00139*
X02664Y00139*
X02664Y00139*
X02664Y0014*
X02664Y0014*
X02664Y0014*
X02664Y00141*
X02664Y00141*
X02702Y00137D02*
D01*
X02703Y00138*
X02703Y00138*
X02703Y00138*
X02703Y00139*
X02704Y00139*
X02704Y0014*
X02704Y0014*
X02704Y00141*
X02704Y00141*
X02704Y00142*
X02704Y00142*
X02704Y00142*
X02821Y00324D02*
D01*
X02821Y00325*
X02821Y00325*
X02821Y00326*
X02821Y00326*
X02821Y00326*
X02821Y00327*
X0282Y00327*
X0282Y00328*
X0282Y00328*
X0282Y00328*
X02819Y00329*
X02819Y00329*
Y0014D02*
D01*
X02819Y0014*
X02819Y00139*
X02819Y00139*
X02819Y00139*
X0282Y00139*
X0282Y00138*
X0282Y00138*
X0282Y00138*
X0282Y00138*
X0282Y00138*
X0282Y00137*
X0282Y00137*
X02854Y0015D02*
D01*
X02854Y00149*
X02855Y00148*
X02855Y00146*
X02855Y00145*
X02855Y00144*
X02856Y00143*
X02856Y00142*
X02857Y00141*
X02858Y00139*
X02859Y00138*
X0286Y00138*
X0286Y00137*
X03019Y00329D02*
D01*
X03019Y00328*
X03019Y00328*
X03019Y00328*
X03019Y00328*
X03018Y00327*
X03018Y00327*
X03018Y00327*
X03018Y00326*
X03018Y00326*
X03018Y00326*
X03018Y00325*
X03018Y00325*
X03017Y00137D02*
D01*
X03018Y00138*
X03018Y00138*
X03018Y00138*
X03018Y00139*
X03019Y00139*
X03019Y0014*
X03019Y0014*
X03019Y00141*
X03019Y00141*
X03019Y00142*
X03019Y00142*
X03019Y00142*
X02979Y00329D02*
D01*
X02979Y00329*
X02979Y00328*
X02979Y00328*
X02979Y00328*
X02979Y00328*
X02979Y00328*
X02979Y00328*
X02979Y00327*
X02979Y00327*
X02979Y00327*
X02979Y00327*
X02979Y00327*
X02978Y00137D02*
D01*
X02978Y00138*
X02978Y00138*
X02979Y00138*
X02979Y00138*
X02979Y00139*
X02979Y00139*
X02979Y00139*
X02979Y0014*
X02979Y0014*
X02979Y0014*
X02979Y00141*
X02979Y00141*
X02979Y00111D02*
D01*
X02979Y00111*
X02979Y00111*
X02979Y00111*
X02979Y00111*
X02979Y00111*
X02979Y00111*
X02979Y00112*
X02979Y00112*
X02979Y00112*
X02979Y00112*
X02979Y00112*
X02979Y00112*
X02467Y00111D02*
D01*
X02467Y00111*
X02467Y00111*
X02467Y00111*
X02467Y00111*
X02467Y00111*
X02467*
D01*
X02467Y00111*
X02467Y00111*
X02468Y00111*
X02468Y00112*
X02468Y00112*
X02468Y00112*
X02468Y00113*
X02468Y00113*
X02468Y00113*
X02468Y00114*
X02468Y00114*
X02468Y00114*
X02664Y00111D02*
D01*
X02664Y00111*
X02664Y00111*
X02664Y00111*
X02664Y00111*
X02664Y00111*
X02664Y00111*
X02664Y00112*
X02664Y00112*
X02664Y00112*
X02664Y00112*
X02664Y00112*
Y00112*
X02854Y00125D02*
D01*
X02854Y00124*
X02855Y00123*
X02855Y00121*
X02855Y0012*
X02856Y00118*
X02856Y00117*
X02857Y00116*
X02858Y00114*
X02858Y00113*
X02859Y00112*
X0286Y00111*
X02861Y00111*
D01*
X02861Y00111*
X02861Y00111*
X02861Y00111*
X02861Y00111*
X02861Y00111*
X02703D02*
D01*
X02703Y00111*
X02703Y00111*
X02704Y00111*
X02704Y00112*
X02704Y00112*
X02704Y00112*
X02704Y00112*
X02704Y00113*
X02704Y00113*
X02704Y00113*
X02704Y00114*
X02704Y00114*
X02468Y00363D02*
Y00405D01*
Y00363D02*
X02468Y00362D01*
X02511Y00363D02*
Y00405D01*
Y00363D02*
X02511Y00362D01*
X0298Y00408D02*
X0298Y00409D01*
X0298Y00409*
X0298Y00364D02*
Y00407D01*
X02818Y00365D02*
Y00403D01*
X02469Y0041D02*
X02469Y0041D01*
X02468Y00405D02*
X02468Y00407D01*
X02469Y0041D02*
X02469Y0041D01*
X02854Y00364D02*
Y00405D01*
X02665Y00364D02*
Y00405D01*
X02704Y00363D02*
X02704Y00362D01*
X02704Y00363D02*
Y00405D01*
X0235Y00364D02*
Y00405D01*
X02389Y00363D02*
X02389Y00362D01*
X02389Y00363D02*
Y00405D01*
X03019Y00363D02*
X03019Y00362D01*
X03019Y00363D02*
Y00405D01*
X02349Y00141D02*
Y00329D01*
X02389Y00142D02*
Y00329D01*
X02468Y00143D02*
Y00329D01*
X02511Y00152D02*
Y00329D01*
X02664Y00141D02*
Y00329D01*
X02704Y00142D02*
Y00329D01*
X02819Y0014D02*
Y00329D01*
X02854Y0015D02*
Y00329D01*
X03019Y00142D02*
Y00329D01*
X02979Y00141D02*
Y00329D01*
G54D50*
X01915Y00137D03*
X02545D03*
X02624D03*
X02899D03*
X03057D03*
X02742D03*
X02938D03*
X02781D03*
X02309D03*
X02427D03*
X02584D03*
X02072D03*
X02033D03*
X01994D03*
X01954D03*
X0219D03*
X02348D03*
X02387D03*
X02466D03*
X02505D03*
X0282D03*
X02663D03*
X0286D03*
X02978D03*
X03017D03*
X02702D03*
X02112D03*
X02151D03*
X01836D03*
X01875D03*
X03096D03*
G54D51*
X01797Y00157D03*
G54D62*
X02632Y02971D03*
Y03042D03*
G54D64*
X02349Y00329D03*
Y00362D03*
X02389D03*
Y00329D03*
X02468D03*
Y00362D03*
X02511D03*
Y00329D03*
X02664Y00362D03*
Y00329D03*
X02704Y00362D03*
Y00329D03*
X02819Y00362D03*
Y00329D03*
X02854D03*
Y00362D03*
X02979D03*
Y00329D03*
X03019Y00362D03*
Y00329D03*
X02711Y03003D03*
Y03036D03*
G54D71*
X02398Y02944D03*
X02327D03*
G54D72*
X02385Y02854D03*
X02351D03*
G54D77*
X02334Y03279D03*
Y032D03*
Y03121D03*
Y03042D03*
X02509Y03279D03*
Y03121D03*
Y032D03*
Y03042D03*
G54D143*
X00299Y01006D03*
Y00806D03*
X00099D03*
Y01006D03*
X00299Y02581D03*
Y02381D03*
X00099D03*
Y02581D03*
X00299Y02056D03*
Y01856D03*
X00099D03*
Y02056D03*
X00299Y01531D03*
Y01331D03*
X00099D03*
Y01531D03*
G54D153*
X02891Y00243D02*
D01*
X0289Y00244*
X02888Y00245*
X02887Y00246*
X02886Y00247*
X02885Y00247*
X02884Y00248*
X02882Y00248*
X02881Y00249*
X0288Y00249*
X02878Y00249*
X02878Y00249*
X02436Y00235D02*
D01*
X02435Y00234*
X02434Y00233*
X02433Y00232*
X02432Y00231*
X02431Y0023*
X0243Y00229*
X0243Y00228*
X02429Y00226*
X02429Y00225*
X02428Y00224*
X02428Y00222*
X02428Y00221*
X02427Y0022*
X02427Y00218*
X02139Y03611D02*
X02342D01*
X02719Y03786D02*
X02719Y03786D01*
X02878Y00249D02*
X02878D01*
X02891Y00243D02*
X02891Y00243D01*
X02898Y00235*
X02427Y00111D02*
Y00218D01*
X02436Y00235D02*
X02447Y00242D01*
X02624Y00235D02*
X02636Y00247D01*
X02799Y00251D02*
X02799D01*
X02546Y00111D02*
Y00244D01*
X03059Y00231D02*
X03079Y00251D01*
X03097*
X01849Y00269D02*
X01876Y00243D01*
X01916Y00111D02*
Y00244D01*
X02934Y00141D02*
Y00224D01*
X02782Y00235D02*
X02799Y00251D01*
X02742Y0024D02*
X02753Y00251D01*
X02923Y00235D02*
X02934Y00224D01*
X02624Y00111D02*
Y00235D01*
X03058Y00139D02*
X03059Y0014D01*
X02934Y00141D02*
X02935Y00141D01*
X02742Y00137D02*
Y0024D01*
X02753Y00251D02*
X02799D01*
X02898Y00138D02*
X02899Y00137D01*
X02898Y00138D02*
Y00235D01*
X02923*
X03058Y00111D02*
Y00139D01*
X03059Y0014D02*
Y00231D01*
X03057Y00111D02*
X03058Y00111D01*
X02782Y00139D02*
Y00235D01*
X02309Y00111D02*
Y00246D01*
X0219Y00112D02*
X02191Y00111D01*
X02781Y00137D02*
X02782Y00139D01*
X02935Y00141D02*
X02938Y00137D01*
X03057D02*
X03058Y00139D01*
X05985Y02782D02*
X05994Y02791D01*
X04511Y02782D02*
X05985D01*
X04503Y02789D02*
X04511Y02782D01*
X03157Y02485D02*
Y0318D01*
Y02485D02*
X03368Y02273D01*
X02774Y03562D02*
X03157Y0318D01*
X07004Y01611D02*
Y02546D01*
X06729Y01336D02*
X07004Y01611D01*
X06424Y03126D02*
X07004Y02546D01*
X03889Y00771D02*
X04339Y0122D01*
X05994Y03556D02*
X06424Y03126D01*
X02774Y03562D02*
Y03566D01*
X02114Y00288D02*
X02151Y00252D01*
X02112Y00255D02*
D01*
Y00137D02*
Y00255D01*
X02151Y00112D02*
Y00252D01*
X01876Y00111D02*
Y00243D01*
X01837Y00111D02*
Y00257D01*
X02151Y00112D02*
X02152Y00111D01*
X01837Y00257D02*
X01849Y00269D01*
X03219Y03806D02*
X03224Y03811D01*
X03218Y03805D02*
X03219Y03806D01*
X02722Y03786D02*
X02784D01*
X02719D02*
X02722D01*
X03571Y02033D02*
Y02058D01*
X02632Y03042D02*
X02638Y03036D01*
X02632Y03042D02*
X02632Y03042D01*
X02509Y03042D02*
X02632D01*
X02638Y03036D02*
X02711D01*
X03571Y0201D02*
Y02033D01*
X0358Y01878D02*
Y02001D01*
Y01878D02*
X03639Y01819D01*
X03571Y0201D02*
X0358Y02001D01*
X03559Y01739D02*
X03639Y01819D01*
X02998Y03811D02*
X03004Y03805D01*
X03218*
X02784Y03786D02*
X02809Y03811D01*
X03534D02*
X03539Y03806D01*
X03368Y02252D02*
X03549Y02071D01*
X03368Y02252D02*
Y02273D01*
X05274Y03511D02*
X05994Y02791D01*
X06284Y02501*
X036Y0106D02*
Y01432D01*
X03559Y01473D02*
X036Y01432D01*
X03559Y01473D02*
Y01739D01*
X036Y0106D02*
X03889Y00771D01*
X04044Y03566D02*
X04254Y03776D01*
X02774Y03566D02*
X04044D01*
X04339Y0122D02*
X06404D01*
X06844Y01661*
X06424Y02181D02*
Y03126D01*
G54D156*
X03958Y04126D03*
X03784D03*
G54D157*
X03294Y04086D03*
X02994D03*
G54D158*
X05327Y02307D03*
X05127D03*
X04927D03*
X04727D03*
X04927Y01007D03*
X05127D03*
X04327Y02307D03*
X05327Y01007D03*
G54D159*
X04327Y01007D03*
G54D160*
X05578Y0089D03*
Y01689D03*
Y02489D03*
X03979D03*
Y0089D03*
X04062Y02595D03*
X0418D03*
X04298D03*
G54D161*
X05723Y04025D03*
Y03844D03*
X069Y03806D03*
Y03589D03*
X06734D03*
Y03806D03*
X06569Y03589D03*
Y03806D03*
G54D162*
X05934Y03937D03*
G54D163*
X06119Y04056D03*
G54D164*
X06119Y03819D03*
G54D165*
X00199Y00906D03*
Y02481D03*
Y01956D03*
Y01431D03*
G54D166*
X03571Y02097D03*
Y01309D03*
X02203Y02438D03*
X01696Y01309D03*
Y02097D03*
X02203Y00958D03*
X0299D03*
X0299Y02438D03*
G54D167*
X02043Y04157D03*
Y04057D03*
X01457Y04153D03*
Y04053D03*
G54D168*
X02043Y04257D03*
X01457Y04253D03*
G54D169*
X069Y04093D03*
X06569D03*
G54D170*
X00285Y04152D03*
Y00368D03*
G54D171*
X04039Y03784D03*
X02494Y02661D03*
X02692Y02721D03*
X02511Y00405D03*
X0261Y00279D03*
X02578D03*
X0298Y00409D03*
X02821Y00407D03*
X02748Y00282D03*
X02469Y0041D03*
X02905Y00279D03*
X02878Y00249D03*
X02692Y00795D03*
X02665D03*
X02854Y00405D03*
X02779Y00279D03*
X02665Y00405D03*
X02704D03*
X0235D03*
X02389D03*
X02937Y00279D03*
X02957Y00251D03*
X03019Y00405D03*
X0274Y00976D03*
X02767D03*
X02732Y00795D03*
X02681Y00976D03*
X02708D03*
X02447Y00242D03*
X02413Y00279D03*
X02444D03*
X02606Y00931D03*
X02625Y00795D03*
X02598D03*
X02636Y00247D03*
X02799Y00251D03*
X02826Y00976D03*
X02799D03*
X02649D03*
X02622D03*
X02759Y00795D03*
X02799D03*
X02826D03*
X02862D03*
X02893D03*
X02409Y01088D03*
X02311Y0109D03*
X02508Y00931D03*
X02409Y00932D03*
X02724Y01093D03*
X02784Y01094D03*
X02842Y01095D03*
X02546Y00244D03*
X03097Y00251D03*
X02475Y02291D03*
X0233Y02215D03*
X01798Y01304D03*
X02606Y01091D03*
X03554Y01841D03*
X03719Y01996D03*
X03894Y01566D03*
X03379Y01386D03*
X01721Y0189D03*
X01671Y01792D03*
X01674Y01989D03*
X02508Y0109D03*
X03413Y01573D03*
X0167Y01595D03*
X01754Y02126D03*
X02409Y02579D03*
X02586Y02569D03*
X03197Y01714D03*
X03439Y0187D03*
X03298Y01971D03*
X02985Y02287D03*
X02702Y02289D03*
X02821Y02601D03*
X01718Y01792D03*
X02881Y02566D03*
X03732Y01418D03*
X03554Y01891D03*
X02253Y02279D03*
X02272Y02463D03*
X01719Y01536D03*
X02311Y00934D03*
X03571Y02033D03*
X03554Y01991D03*
X02942Y02286D03*
X02841Y02263D03*
X02394Y0272D03*
X01567Y01285D03*
X01675Y01891D03*
X01568Y02067D03*
X02783Y02429D03*
X03719Y01921D03*
X03773Y01666D03*
X02599Y02436D03*
X02494Y02696D03*
X02894Y02431D03*
X02665Y01092D03*
X02475Y02456D03*
X03414Y01805D03*
X03404Y01363D03*
X02579Y02281D03*
X02685Y02311D03*
X0359Y01662D03*
X02404Y02412D03*
X02803Y02307D03*
X01716Y01399D03*
X01721Y01989D03*
X01619Y02121D03*
X03549Y01413D03*
X02488Y02413D03*
X02726Y02293D03*
X01822Y01674D03*
X0167Y01694D03*
X01884Y02071D03*
X02901Y01095D03*
X0292Y02428D03*
X01893Y01693D03*
X03594Y01514D03*
X0245Y02282D03*
X02409Y02314D03*
X02958Y02621D03*
X03406Y01461D03*
X0341Y01713D03*
X03252Y01661D03*
X02933Y00953D03*
X02871Y02297D03*
X02685Y02568D03*
X03571Y02058D03*
X03804Y0184D03*
X01879Y01811D03*
X03554Y01941D03*
X03392Y01871D03*
X03407Y01411D03*
X02575Y02412D03*
X02499Y02236D03*
X02409Y02283D03*
X02783Y02568D03*
X02948Y02456D03*
X03549Y01441D03*
X03718Y01713D03*
X02624Y02461D03*
X01897Y01516D03*
X03834Y01481D03*
X03864Y01511D03*
X03924Y01536D03*
X03719Y01766D03*
X03329Y01826D03*
X02645Y02274D03*
X02665Y02291D03*
X01721Y01694D03*
X01671Y01399D03*
X02581Y02308D03*
X03803Y01691D03*
X03224Y01661D03*
X02252Y02613D03*
X01718Y01497D03*
X01714Y01595D03*
X01671Y01497D03*
X02321Y02586D03*
X03379Y01336D03*
X01797Y00355D03*
X02034Y00246D03*
X01916Y00244D03*
X02309Y00246D03*
X0333Y03301D03*
X0412Y03594D03*
X01393Y01816D03*
X0099Y00687D03*
X04794Y02808D03*
X03183Y03135D03*
X03277Y02963D03*
X03197Y0297D03*
X03491Y03103D03*
X03188Y03187D03*
X0323Y03235D03*
X03358Y03448D03*
X03068Y03395D03*
X02419Y02788D03*
X02146Y02753D03*
X03275Y03141D03*
X03056Y01811D03*
X02413Y03295D03*
X02254Y03536D03*
X02579Y03486D03*
X02389Y03481D03*
X02321Y03361D03*
X02434Y03546D03*
X02634Y03406D03*
X02631Y02876D03*
X02591Y03186D03*
X0259Y03288D03*
X00996Y02256D03*
X02004Y01336D03*
X02028Y01361D03*
X02549Y01755D03*
X02418Y03118D03*
X02414Y03199D03*
X02462Y03172D03*
X02473Y0298D03*
X02146Y04103D03*
X02253Y04086D03*
X01408Y0398D03*
X01345Y04175D03*
X00996Y01187D03*
X00988Y01717D03*
X00937Y02317D03*
X02353Y04017D03*
X01726Y04329D03*
X01788D03*
X04477Y03135D03*
X04064Y02722D03*
X06628Y01372D03*
X04039Y02406D03*
X06974Y01939D03*
X04134Y01651D03*
X03994Y01551D03*
X04134Y01751D03*
X04151Y01623D03*
X03968Y01671D03*
X03969Y01552D03*
X03944Y01816D03*
X04131Y01686D03*
X04179Y01601D03*
X04034Y01546D03*
X03996Y01711D03*
X04064Y01796D03*
Y01511D03*
X03263Y03303D03*
X0396Y02724D03*
X01569Y04171D03*
X02076Y00255D03*
Y00287D03*
X02112D03*
X02151D03*
X02112Y00255D03*
X02151D03*
X01832D03*
X01852D03*
X01872D03*
X01832Y00287D03*
X01852D03*
X01872D03*
X06253Y02909D03*
X06647Y03129D03*
X05267Y04088D03*
X04339Y02725D03*
X04503Y02789D03*
X02231Y02584D03*
X05994Y03552D03*
X04049Y03665D03*
X03829Y03806D03*
X05577Y02214D03*
X02694Y01481D03*
X02384Y01941D03*
X0383Y03762D03*
X06334Y03266D03*
X03744Y03261D03*
X03395Y04222D03*
X04272Y03135D03*
X05634Y02236D03*
X02626Y0177D03*
X06304Y03121D03*
X03939D03*
X02139Y03738D03*
X04208Y03135D03*
X02604Y01734D03*
X06626Y03032D03*
X04152Y03135D03*
X02299Y01916D03*
X02724Y03521D03*
X01248Y02D03*
X02579Y0179D03*
X04068Y03135D03*
X02674Y03501D03*
X04234Y02725D03*
X06456Y03009D03*
X01691Y04079D03*
X03642Y00636D03*
X02259Y03261D03*
X03374Y03273D03*
X03368Y0305D03*
X06476Y03231D03*
X04333Y03135D03*
X01557Y04229D03*
X06282Y03226D03*
X03806Y03235D03*
X01261Y02482D03*
X04114Y03135D03*
X06648Y03341D03*
X02888Y04221D03*
X0337Y02888D03*
X02258Y03741D03*
X01749Y0411D03*
X0257Y04283D03*
X01459Y03147D03*
X0144Y03557D03*
X01903Y04018D03*
X0229Y04217D03*
X0388Y03109D03*
X03623Y02587D03*
X03622Y03486D03*
X03491Y03297D03*
X03542Y03319D03*
X03344Y02996D03*
X03744Y03342D03*
X03653Y03293D03*
X03394Y03447D03*
X03436Y03457D03*
X03717Y03072D03*
X02799Y03616D03*
X03589Y01711D03*
X05733Y03556D03*
X05676Y03546D03*
X03603Y00682D03*
X02478Y00937D03*
X06548Y01531D03*
X06602Y01612D03*
Y01672D03*
Y01722D03*
X06601Y01777D03*
X06685Y01828D03*
X06699Y01881D03*
X06949Y02095D03*
X06607Y02176D03*
X06395Y02111D03*
X06048Y02171D03*
X06004Y02434D03*
X06274Y02391D03*
X06398Y02453D03*
X06397Y02501D03*
X06396Y02556D03*
X06397Y0261D03*
X06398Y02657D03*
X06372Y02909D03*
X0491Y04203D03*
X04387Y04206D03*
X03777Y04023D03*
X04085Y03892D03*
X04194Y03884D03*
X04431Y03135D03*
X0286Y03787D03*
X02724Y03729D03*
X03531Y0366D03*
X03269Y03788D03*
X01242Y01472D03*
X01256Y00942D03*
X00654Y0079D03*
X00655Y01028D03*
X00654Y01314D03*
X00653Y01551D03*
X00654Y01839D03*
Y02073D03*
Y02365D03*
X00653Y02593D03*
X02206Y01298D03*
X02205Y032D03*
X02502Y01316D03*
X02525Y02463D03*
X03342Y02263D03*
X03498Y02341D03*
X02429Y02621D03*
X01004Y00906D03*
X02446Y01437D03*
X01008Y0143D03*
X02409Y01967D03*
X01009Y01956D03*
X0102Y02481D03*
X02643Y01616D03*
X02666Y0164D03*
X01884Y03601D03*
X01754Y03661D03*
X03424Y03636D03*
X01549Y03621D03*
X03239Y03596D03*
X01574D03*
X03539Y03806D03*
X03219D03*
X02722Y03786D03*
X02139Y03611D03*
X02084Y03896D03*
X02083Y01411D03*
X02059Y01386D03*
Y03871D03*
X02029Y03836D03*
X01294Y04256D03*
X02004Y03816D03*
X02234Y03506D03*
X03529Y03481D03*
X05274Y03511D03*
X06284Y02501D03*
X02679Y03661D03*
X02774Y03566D03*
X02993Y03751D03*
X03699D03*
X03014Y03831D03*
X03699Y03836D03*
X04254Y03776D03*
X02894Y01561D03*
X02919Y01536D03*
X02274Y01506D03*
X02719Y01591D03*
X03724Y01675D03*
X06844Y01661D03*
X06424Y02181D03*
X06309Y03199D03*
X06339Y03151D03*
X04754Y04115D03*
X01779Y04156D03*
X03504Y04086D03*
X03854Y03151D03*
X03829Y03176D03*
X03799Y03201D03*
X06439Y03191D03*
X06354Y03331D03*
X06444Y03291D03*
X03302Y03344D03*
X06409Y03371D03*
X06447Y03396D03*
X06479Y03426D03*
X06509Y03456D03*
X03469D03*
X01849Y03701D03*
X06294D03*
G54D172*
X02531Y03853D03*
Y0283D03*
X00149D03*
Y03853D03*
G54D173*
X0213Y00268D03*
X01851Y00269D03*
M02*